G04 ================== begin FILE IDENTIFICATION RECORD ==================*
G04 Layout Name:  DA0T6MTH8C0_t6m_tray_bp_c_brd_103112_274.brd*
G04 Film Name:    sst.art*
G04 File Format:  Gerber RS274X*
G04 File Origin:  Cadence Allegro 16.3-S048*
G04 Origin Date:  Tue Nov 26 11:26:40 2013*
G04 *
G04 Layer:  BOARD GEOMETRY/OUTLINE*
G04 Layer:  DRAWING FORMAT/TITLE_BLOCK*
G04 Layer:  MANUFACTURING/TP_TEXT_TOP*
G04 Layer:  REF DES/SILKSCREEN_TOP*
G04 Layer:  PACKAGE GEOMETRY/SILKSCREEN_TOP*
G04 Layer:  MANUFACTURING/PHOTOPLOT_OUTLINE*
G04 Layer:  DRAWING FORMAT/TITLE_DATA_SST*
G04 Layer:  BOARD GEOMETRY/SILKSCREEN_TOP*
G04 *
G04 Offset:    (0.00 0.00)*
G04 Mirror:    No*
G04 Mode:      Positive*
G04 Rotation:  0*
G04 FullContactRelief:  No*
G04 UndefLineWidth:     6.00*
G04 ================== end FILE IDENTIFICATION RECORD ====================*
%FSLAX25Y25*MOIN*%
%IR0*IPPOS*OFA0.00000B0.00000*MIA0B0*SFA1.00000B1.00000*%
%ADD10C,.006*%
%ADD11C,.008*%
G75*
%LPD*%
G75*
G36*
G01X25058Y77012D02*
X30258Y74712D01*
Y79512D01*
X25058Y77012D01*
G37*
G36*
G01X25113Y95213D02*
X30417Y97264D01*
X27022Y100658D01*
X25113Y95213D01*
G37*
G36*
G01X31632Y82683D02*
Y94483D01*
X37032D01*
Y82683D01*
X31632D01*
G37*
G36*
G01X56833Y149910D02*
X53078Y157422D01*
X60589D01*
X56833Y149910D01*
G37*
G36*
G01X94303Y58298D02*
X91303Y52298D01*
X97303D01*
X94303Y58298D01*
G37*
G36*
G01X124958Y92812D02*
X130158Y90512D01*
Y95312D01*
X124958Y92812D01*
G37*
G36*
G01X125425Y107084D02*
X130729Y109134D01*
X127335Y112529D01*
X125425Y107084D01*
G37*
G36*
G01X275802Y45250D02*
Y38150D01*
Y38104D01*
X282702Y41850D01*
X275802Y45250D01*
G37*
G36*
G01X335941Y86668D02*
X338941Y94168D01*
X332941D01*
X335941Y86668D01*
G37*
G36*
G01X425029Y77853D02*
X427229Y83453D01*
X422929D01*
X425029Y77853D01*
G37*
G36*
G01X447544Y178094D02*
X461044Y173594D01*
Y182594D01*
X447544Y178094D01*
G37*
G36*
G01X514926Y10268D02*
Y6268D01*
X510926Y8268D01*
X514926Y10268D01*
G37*
G36*
G01X522309Y152500D02*
X530609Y150000D01*
Y154900D01*
X522309Y152500D01*
G37*
G36*
G01X581081Y24209D02*
X586102Y19189D01*
X586134Y19156D01*
X588365Y26684D01*
X581081Y24209D01*
G37*
G36*
G01X574321Y77854D02*
X576521Y83454D01*
X572221D01*
X574321Y77854D01*
G37*
G36*
G01X606036Y177894D02*
X619536Y173394D01*
Y182394D01*
X606036Y177894D01*
G37*
G36*
G01X697445Y10268D02*
Y6268D01*
X693445Y8268D01*
X697445Y10268D01*
G37*
G36*
G01X731575Y117050D02*
X738575Y121050D01*
Y113050D01*
X731575Y117050D01*
G37*
G36*
G01X763358Y76194D02*
X758858Y62694D01*
X767858D01*
X763358Y76194D01*
G37*
G36*
G01X781317Y111850D02*
X788317Y115850D01*
Y107850D01*
X781317Y111850D01*
G37*
G36*
G01X831487Y29989D02*
Y53611D01*
X1028337D01*
Y29989D01*
X831487D01*
G37*
G36*
G01X1145881Y45250D02*
Y38150D01*
Y38104D01*
X1152781Y41850D01*
X1145881Y45250D01*
G37*
G36*
G01X1205941Y88568D02*
X1208941Y96068D01*
X1202941D01*
X1205941Y88568D01*
G37*
G36*
G01X1295108Y77854D02*
X1297308Y83454D01*
X1293008D01*
X1295108Y77854D01*
G37*
G36*
G01X1312523Y179894D02*
X1326023Y175394D01*
Y184394D01*
X1312523Y179894D01*
G37*
G36*
G01X1385005Y10268D02*
Y6268D01*
X1381005Y8268D01*
X1385005Y10268D01*
G37*
G36*
G01X1393288Y151300D02*
X1401588Y148800D01*
Y153700D01*
X1393288Y151300D01*
G37*
G36*
G01X1451391Y24553D02*
X1456411Y19532D01*
X1456444Y19500D01*
X1458674Y27028D01*
X1451391Y24553D01*
G37*
G36*
G01X1444400Y77853D02*
X1446600Y83453D01*
X1442300D01*
X1444400Y77853D01*
G37*
G36*
G01X1475714Y179794D02*
X1489214Y175294D01*
Y184294D01*
X1475714Y179794D01*
G37*
G36*
G01X1567524Y10268D02*
Y6268D01*
X1563524Y8268D01*
X1567524Y10268D01*
G37*
G36*
G01X1576553Y111850D02*
X1583553Y115850D01*
Y107850D01*
X1576553Y111850D01*
G37*
G36*
G01X1637389Y77044D02*
X1643753Y64317D01*
X1650117Y70680D01*
X1637389Y77044D01*
G37*
G36*
G01X1674875Y104193D02*
X1682653Y102072D01*
X1676996Y96415D01*
X1674875Y104193D01*
G37*
G54D10*
G01X1683504Y165354D02*
Y190512D01*
G03X1675630Y198386I-7874J0D01*
G01X1503898D01*
X1502406Y198679D01*
X1501137Y199516D01*
X1500279Y200772D01*
X1499930Y202268D01*
X1499661Y203554D01*
X1498808Y204831D01*
X1497530Y205685D01*
X1496024Y205984D01*
X1468465D01*
G03X1464528Y202047I0J-3937D01*
G01Y200000D01*
G02X1460591Y196063I-3937J0D01*
G01X1401535D01*
G02X1397598Y200000I0J3937D01*
G01Y202047D01*
G03X1393661Y205984I-3937J0D01*
G01X1319173D01*
G03X1315236Y202047I0J-3937D01*
G01Y200000D01*
G02X1311299Y196063I-3937J0D01*
G01X1252244D01*
G02X1248307Y200000I0J3937D01*
G01Y202047D01*
G03X1244370Y205984I-3937J0D01*
G01X807047D01*
X805541Y205685D01*
X804263Y204831D01*
X803410Y203554D01*
X803141Y202268D01*
X802792Y200772D01*
X801934Y199516D01*
X800665Y198679D01*
X799173Y198386D01*
X633819D01*
X632327Y198679D01*
X631058Y199516D01*
X630200Y200772D01*
X629851Y202268D01*
X629582Y203554D01*
X628729Y204831D01*
X627451Y205685D01*
X625945Y205984D01*
X598386D01*
G03X594449Y202047I0J-3937D01*
G01Y200000D01*
G02X590512Y196063I-3937J0D01*
G01X531457D01*
G02X527520Y200000I0J3937D01*
G01Y202047D01*
G03X523583Y205984I-3937J0D01*
G01X449094D01*
G03X445157Y202047I0J-3937D01*
G01Y200000D01*
G02X441220Y196063I-3937J0D01*
G01X382165D01*
G02X378228Y200000I0J3937D01*
G01Y202047D01*
G03X374291Y205984I-3937J0D01*
G01X228661D01*
G03X220787Y198110I0J-7874D01*
G01Y170551D01*
G02X216850Y166614I-3937J0D01*
G01X208976D01*
G02X205039Y170551I0J3937D01*
G01Y203937D01*
X199134Y209842D01*
X49803D01*
X43898Y203937D01*
Y167913D01*
G02X41142I-1378J0D01*
G01Y203937D01*
X37205Y207874D01*
X35236Y209842D01*
X5906D01*
X3937Y207874D01*
X0Y203937D01*
Y7874D01*
G03X7874Y0I7874J0D01*
G01X1680354D01*
G03X1688228Y7874I0J7874D01*
G01Y39370D01*
G03X1686260Y41339I-1969J0D01*
G01X1685472D01*
G02X1683504Y43307I0J1968D01*
G01Y122047D01*
G03X1681535Y124016I-1969J0D01*
G01X1675236D01*
G02X1673268Y125984I0J1968D01*
G01Y161417D01*
G02X1675236Y163386I1968J1D01*
G01X1681535D01*
G03X1683504Y165354I1J1968D01*
G01X10433Y114173D02*
Y128497D01*
G02X25000I7283J9298D01*
G01Y114173D01*
G02X10433I-7284J0D01*
G01X306929Y163386D02*
Y177710D01*
G02X321496I7283J9298D01*
G01Y163386D01*
G02X306929I-7283J0D01*
G01X457212Y-338900D02*
Y-343900D01*
G01X455755Y-338900D02*
X458669D01*
G01X463579Y-343900D02*
X461045D01*
Y-338900D01*
X463579D01*
G01X462565Y-341317D02*
X461045D01*
G01X466145Y-338900D02*
Y-343900D01*
X468679D01*
G01X472512Y-344067D02*
X472385Y-343983D01*
Y-343817D01*
X472512Y-343733D01*
X472639Y-343817D01*
Y-343983D01*
X472512Y-344067D01*
G01Y-341817D02*
X472385Y-341733D01*
Y-341567D01*
X472512Y-341483D01*
X472639Y-341567D01*
Y-341733D01*
X472512Y-341817D01*
G01X477295Y-345567D02*
X476662Y-344733D01*
X476345Y-343900D01*
Y-340567D01*
X476662Y-339733D01*
X477295Y-338900D01*
G01X482712D02*
X482205Y-339067D01*
X481825Y-339483D01*
X481572Y-339983D01*
X481382Y-340650D01*
X481319Y-341400D01*
X481382Y-342150D01*
X481572Y-342817D01*
X481825Y-343317D01*
X482205Y-343733D01*
X482712Y-343900D01*
X483219Y-343733D01*
X483599Y-343317D01*
X483852Y-342817D01*
X484042Y-342150D01*
X484105Y-341400D01*
X484042Y-340650D01*
X483852Y-339983D01*
X483599Y-339483D01*
X483219Y-339067D01*
X482712Y-338900D01*
G01X486419Y-342900D02*
X486799Y-343483D01*
X487305Y-343817D01*
X487875Y-343900D01*
X488382Y-343817D01*
X488889Y-343400D01*
X489205Y-342900D01*
X489269Y-342400D01*
X489142Y-341817D01*
X488699Y-341400D01*
X488255Y-341233D01*
X487685D01*
G01X488255D02*
X488635Y-340983D01*
X488952Y-340567D01*
X489079Y-340067D01*
X488952Y-339567D01*
X488635Y-339150D01*
X488065Y-338900D01*
X487495Y-338983D01*
X486925Y-339317D01*
G01X493229Y-345567D02*
X493862Y-344733D01*
X494179Y-343900D01*
Y-340567D01*
X493862Y-339733D01*
X493229Y-338900D01*
G01X496619Y-342900D02*
X496999Y-343483D01*
X497505Y-343817D01*
X498075Y-343900D01*
X498582Y-343817D01*
X499089Y-343400D01*
X499405Y-342900D01*
X499469Y-342400D01*
X499342Y-341817D01*
X498899Y-341400D01*
X498455Y-341233D01*
X497885D01*
G01X498455D02*
X498835Y-340983D01*
X499152Y-340567D01*
X499279Y-340067D01*
X499152Y-339567D01*
X498835Y-339150D01*
X498265Y-338900D01*
X497695Y-338983D01*
X497125Y-339317D01*
G01X501909Y-339733D02*
X502289Y-339233D01*
X502732Y-338983D01*
X503239Y-338900D01*
X503872Y-339067D01*
X504315Y-339483D01*
X504442Y-339983D01*
X504379Y-340483D01*
X504125Y-340900D01*
X502859Y-341733D01*
X502289Y-342317D01*
X501909Y-343150D01*
X501782Y-343900D01*
X504442D01*
G01X508085D02*
X508212Y-342817D01*
X508402Y-341900D01*
X508655Y-341067D01*
X508972Y-340150D01*
X509479Y-338900D01*
X506945D01*
G01X512489Y-342233D02*
X514135D01*
G01X517209Y-339733D02*
X517589Y-339233D01*
X518032Y-338983D01*
X518539Y-338900D01*
X519172Y-339067D01*
X519615Y-339483D01*
X519742Y-339983D01*
X519679Y-340483D01*
X519425Y-340900D01*
X518159Y-341733D01*
X517589Y-342317D01*
X517209Y-343150D01*
X517082Y-343900D01*
X519742D01*
G01X522119Y-342900D02*
X522499Y-343483D01*
X523005Y-343817D01*
X523575Y-343900D01*
X524082Y-343817D01*
X524589Y-343400D01*
X524905Y-342900D01*
X524969Y-342400D01*
X524842Y-341817D01*
X524399Y-341400D01*
X523955Y-341233D01*
X523385D01*
G01X523955D02*
X524335Y-340983D01*
X524652Y-340567D01*
X524779Y-340067D01*
X524652Y-339567D01*
X524335Y-339150D01*
X523765Y-338900D01*
X523195Y-338983D01*
X522625Y-339317D01*
G01X529372Y-343900D02*
Y-338900D01*
X527029Y-342483D01*
X530195D01*
G01X532319Y-343150D02*
X532699Y-343567D01*
X533142Y-343817D01*
X533712Y-343900D01*
X534282Y-343733D01*
X534725Y-343400D01*
X535042Y-342817D01*
X535105Y-342150D01*
X534979Y-341483D01*
X534662Y-341067D01*
X534219Y-340733D01*
X533775Y-340650D01*
X533332Y-340733D01*
X532762Y-341067D01*
X532952Y-338900D01*
X534662D01*
G01X542709Y-343900D02*
Y-338900D01*
X545115D01*
G01X544229Y-341317D02*
X542709D01*
G01X547429Y-343900D02*
X549012Y-338900D01*
X550595Y-343900D01*
G01X550025Y-342150D02*
X547999D01*
G01X552782Y-343900D02*
X555442Y-338900D01*
G01X552782D02*
X555442Y-343900D01*
G01X559212Y-344067D02*
X559085Y-343983D01*
Y-343817D01*
X559212Y-343733D01*
X559339Y-343817D01*
Y-343983D01*
X559212Y-344067D01*
G01Y-341817D02*
X559085Y-341733D01*
Y-341567D01*
X559212Y-341483D01*
X559339Y-341567D01*
Y-341733D01*
X559212Y-341817D01*
G01X563995Y-345567D02*
X563362Y-344733D01*
X563045Y-343900D01*
Y-340567D01*
X563362Y-339733D01*
X563995Y-338900D01*
G01X569412D02*
X568905Y-339067D01*
X568525Y-339483D01*
X568272Y-339983D01*
X568082Y-340650D01*
X568019Y-341400D01*
X568082Y-342150D01*
X568272Y-342817D01*
X568525Y-343317D01*
X568905Y-343733D01*
X569412Y-343900D01*
X569919Y-343733D01*
X570299Y-343317D01*
X570552Y-342817D01*
X570742Y-342150D01*
X570805Y-341400D01*
X570742Y-340650D01*
X570552Y-339983D01*
X570299Y-339483D01*
X569919Y-339067D01*
X569412Y-338900D01*
G01X573119Y-342900D02*
X573499Y-343483D01*
X574005Y-343817D01*
X574575Y-343900D01*
X575082Y-343817D01*
X575589Y-343400D01*
X575905Y-342900D01*
X575969Y-342400D01*
X575842Y-341817D01*
X575399Y-341400D01*
X574955Y-341233D01*
X574385D01*
G01X574955D02*
X575335Y-340983D01*
X575652Y-340567D01*
X575779Y-340067D01*
X575652Y-339567D01*
X575335Y-339150D01*
X574765Y-338900D01*
X574195Y-338983D01*
X573625Y-339317D01*
G01X579929Y-345567D02*
X580562Y-344733D01*
X580879Y-343900D01*
Y-340567D01*
X580562Y-339733D01*
X579929Y-338900D01*
G01X583319Y-342900D02*
X583699Y-343483D01*
X584205Y-343817D01*
X584775Y-343900D01*
X585282Y-343817D01*
X585789Y-343400D01*
X586105Y-342900D01*
X586169Y-342400D01*
X586042Y-341817D01*
X585599Y-341400D01*
X585155Y-341233D01*
X584585D01*
G01X585155D02*
X585535Y-340983D01*
X585852Y-340567D01*
X585979Y-340067D01*
X585852Y-339567D01*
X585535Y-339150D01*
X584965Y-338900D01*
X584395Y-338983D01*
X583825Y-339317D01*
G01X588735Y-343317D02*
X589179Y-343733D01*
X589685Y-343900D01*
X590192Y-343733D01*
X590635Y-343233D01*
X590952Y-342483D01*
X591079Y-341733D01*
Y-340817D01*
X590952Y-340067D01*
X590635Y-339400D01*
X590255Y-339067D01*
X589812Y-338900D01*
X589305Y-339067D01*
X588925Y-339400D01*
X588672Y-339900D01*
X588545Y-340567D01*
X588672Y-341150D01*
X588989Y-341733D01*
X589369Y-342067D01*
X589812Y-342150D01*
X590319Y-341983D01*
X590699Y-341567D01*
X591079Y-340817D01*
G01X594785Y-343900D02*
X594912Y-342817D01*
X595102Y-341900D01*
X595355Y-341067D01*
X595672Y-340150D01*
X596179Y-338900D01*
X593645D01*
G01X599189Y-342233D02*
X600835D01*
G01X603719Y-342900D02*
X604099Y-343483D01*
X604605Y-343817D01*
X605175Y-343900D01*
X605682Y-343817D01*
X606189Y-343400D01*
X606505Y-342900D01*
X606569Y-342400D01*
X606442Y-341817D01*
X605999Y-341400D01*
X605555Y-341233D01*
X604985D01*
G01X605555D02*
X605935Y-340983D01*
X606252Y-340567D01*
X606379Y-340067D01*
X606252Y-339567D01*
X605935Y-339150D01*
X605365Y-338900D01*
X604795Y-338983D01*
X604225Y-339317D01*
G01X609009Y-341817D02*
X609452Y-341233D01*
X609832Y-340900D01*
X610339Y-340733D01*
X610782Y-340900D01*
X611099Y-341233D01*
X611352Y-341733D01*
X611415Y-342317D01*
X611352Y-342817D01*
X611099Y-343317D01*
X610719Y-343733D01*
X610275Y-343900D01*
X609769Y-343733D01*
X609325Y-343233D01*
X609072Y-342483D01*
X609009Y-341650D01*
X609135Y-340567D01*
X609325Y-339983D01*
X609642Y-339400D01*
X610085Y-338983D01*
X610529Y-338900D01*
X610972Y-339067D01*
X611289Y-339483D01*
G01X615312Y-343900D02*
Y-338900D01*
X614552Y-339900D01*
G01Y-343900D02*
X616072D01*
G01X621172D02*
Y-338900D01*
X618829Y-342483D01*
X621995D01*
G01X445212Y-273900D02*
Y-348900D01*
X945212D01*
Y-273900D01*
X445212D01*
G01X640212D02*
Y-348900D01*
G01Y-323900D02*
X743212D01*
Y-298900D01*
G01X640212D02*
X743212D01*
G01Y-273900D02*
Y-348900D01*
G01X745212Y-273900D02*
Y-348900D01*
G01X750719Y-333900D02*
Y-328900D01*
X751985D01*
X752492Y-329150D01*
X752872Y-329483D01*
X753189Y-329983D01*
X753442Y-330567D01*
X753505Y-331400D01*
X753442Y-332233D01*
X753189Y-332817D01*
X752872Y-333317D01*
X752492Y-333650D01*
X751985Y-333900D01*
X750719D01*
G01X755629D02*
X757212Y-328900D01*
X758795Y-333900D01*
G01X758225Y-332150D02*
X756199D01*
G01X762312Y-328900D02*
Y-333900D01*
G01X760855Y-328900D02*
X763769D01*
G01X768679Y-333900D02*
X766145D01*
Y-328900D01*
X768679D01*
G01X767665Y-331317D02*
X766145D01*
G01X772512Y-334067D02*
X772385Y-333983D01*
Y-333817D01*
X772512Y-333733D01*
X772639Y-333817D01*
Y-333983D01*
X772512Y-334067D01*
G01Y-331817D02*
X772385Y-331733D01*
Y-331567D01*
X772512Y-331483D01*
X772639Y-331567D01*
Y-331733D01*
X772512Y-331817D01*
G01X745212Y-323900D02*
X945212D01*
G01X750845Y-308900D02*
Y-303900D01*
X752365D01*
X752872Y-304150D01*
X753252Y-304733D01*
X753379Y-305400D01*
X753252Y-306067D01*
X752935Y-306567D01*
X752365Y-306817D01*
X750845D01*
G01X756072Y-309067D02*
X758352Y-303900D01*
G01X760855Y-308900D02*
Y-303900D01*
X763769Y-308900D01*
Y-303900D01*
G01X767412Y-309067D02*
X767285Y-308983D01*
Y-308817D01*
X767412Y-308733D01*
X767539Y-308817D01*
Y-308983D01*
X767412Y-309067D01*
G01Y-306817D02*
X767285Y-306733D01*
Y-306567D01*
X767412Y-306483D01*
X767539Y-306567D01*
Y-306733D01*
X767412Y-306817D01*
G01X745212Y-298900D02*
X945212D01*
G01X750845Y-283900D02*
Y-278900D01*
X752365D01*
X752872Y-279150D01*
X753252Y-279733D01*
X753379Y-280400D01*
X753252Y-281067D01*
X752935Y-281567D01*
X752365Y-281817D01*
X750845D01*
G01X755945Y-283900D02*
Y-278900D01*
X757529D01*
X758035Y-279150D01*
X758352Y-279483D01*
X758479Y-280150D01*
X758352Y-280817D01*
X757972Y-281233D01*
X757529Y-281483D01*
X755945D01*
G01X757529D02*
X758479Y-283900D01*
G01X762312D02*
X761805Y-283817D01*
X761362Y-283483D01*
X760982Y-282983D01*
X760729Y-282400D01*
X760602Y-281733D01*
Y-281067D01*
X760729Y-280400D01*
X760982Y-279817D01*
X761362Y-279317D01*
X761805Y-278983D01*
X762312Y-278900D01*
X762819Y-278983D01*
X763262Y-279317D01*
X763642Y-279817D01*
X763895Y-280400D01*
X764022Y-281067D01*
Y-281733D01*
X763895Y-282400D01*
X763642Y-282983D01*
X763262Y-283483D01*
X762819Y-283817D01*
X762312Y-283900D01*
G01X766145Y-282900D02*
X766462Y-283400D01*
X766842Y-283733D01*
X767285Y-283900D01*
X767792Y-283733D01*
X768172Y-283400D01*
X768552Y-282900D01*
X768679Y-282233D01*
Y-278900D01*
G01X773779Y-283900D02*
X771245D01*
Y-278900D01*
X773779D01*
G01X772765Y-281317D02*
X771245D01*
G01X779005Y-279317D02*
X778625Y-279067D01*
X778182Y-278900D01*
X777675D01*
X777105Y-279150D01*
X776662Y-279567D01*
X776345Y-280067D01*
X776092Y-280900D01*
X776029Y-281650D01*
X776155Y-282400D01*
X776345Y-282900D01*
X776725Y-283400D01*
X777169Y-283733D01*
X777612Y-283900D01*
X778055D01*
X778499Y-283733D01*
X778879Y-283483D01*
X779195Y-283150D01*
G01X782712Y-278900D02*
Y-283900D01*
G01X781255Y-278900D02*
X784169D01*
G01X787812Y-284067D02*
X787685Y-283983D01*
Y-283817D01*
X787812Y-283733D01*
X787939Y-283817D01*
Y-283983D01*
X787812Y-284067D01*
G01Y-281817D02*
X787685Y-281733D01*
Y-281567D01*
X787812Y-281483D01*
X787939Y-281567D01*
Y-281733D01*
X787812Y-281817D01*
G01X776772Y18504D02*
Y32533D01*
G02X790551I6889J9593D01*
G01Y18504D01*
G02X776772I-6890J0D01*
G01X819134Y163386D02*
Y177415D01*
G02X832913I6890J9593D01*
G01Y163386D01*
G02X819134I-6889J0D01*
G01X860212Y-323900D02*
Y-348900D01*
G01X865845Y-333900D02*
Y-328900D01*
X867429D01*
X867935Y-329150D01*
X868252Y-329483D01*
X868379Y-330150D01*
X868252Y-330817D01*
X867872Y-331233D01*
X867429Y-331483D01*
X865845D01*
G01X867429D02*
X868379Y-333900D01*
G01X873479D02*
X870945D01*
Y-328900D01*
X873479D01*
G01X872465Y-331317D02*
X870945D01*
G01X875729Y-328900D02*
X877312Y-333900D01*
X878895Y-328900D01*
G01X882412Y-334067D02*
X882285Y-333983D01*
Y-333817D01*
X882412Y-333733D01*
X882539Y-333817D01*
Y-333983D01*
X882412Y-334067D01*
G01Y-331817D02*
X882285Y-331733D01*
Y-331567D01*
X882412Y-331483D01*
X882539Y-331567D01*
Y-331733D01*
X882412Y-331817D01*
G01X909212Y-323900D02*
Y-348900D01*
G01X1094331Y18504D02*
Y32828D01*
G02X1108898I7283J9298D01*
G01Y18504D01*
G02X1094331I-7283J0D01*
G01X1177008Y163386D02*
Y177710D01*
G02X1191575I7284J9298D01*
G01Y163386D01*
G02X1177008I-7283J0D01*
G01X-471400Y-391900D02*
Y1528800D01*
X2244200D01*
Y-391900D01*
X-471400D01*
G01X49213Y18504D02*
G03I-31496J0D01*
G01X1834Y74325D02*
X2064Y74635D01*
X2332Y74790D01*
X2639Y74842D01*
X3022Y74739D01*
X3290Y74480D01*
X3367Y74170D01*
X3329Y73860D01*
X3175Y73602D01*
X2409Y73085D01*
X2064Y72724D01*
X1834Y72207D01*
X1757Y71742D01*
X3367D01*
G01X3895Y65162D02*
X4087Y64852D01*
X4317Y64645D01*
X4585Y64542D01*
X4892Y64645D01*
X5122Y64852D01*
X5352Y65162D01*
X5429Y65575D01*
Y67642D01*
G01X6995Y64542D02*
Y67642D01*
X7915D01*
X8222Y67487D01*
X8452Y67125D01*
X8529Y66712D01*
X8452Y66299D01*
X8260Y65989D01*
X7915Y65834D01*
X6995D01*
G01X10862Y64542D02*
X11130Y64594D01*
X11437Y64749D01*
X11629Y65007D01*
X11705Y65369D01*
X11629Y65730D01*
X11399Y66040D01*
X11054Y66195D01*
X10670D01*
X10440Y66299D01*
X10249Y66557D01*
X10172Y66919D01*
X10287Y67280D01*
X10555Y67539D01*
X10862Y67642D01*
X11169Y67539D01*
X11437Y67280D01*
X11552Y66919D01*
X11475Y66557D01*
X11284Y66299D01*
X11054Y66195D01*
X10670D01*
X10325Y66040D01*
X10095Y65730D01*
X10019Y65369D01*
X10095Y65007D01*
X10287Y64749D01*
X10594Y64594D01*
X10862Y64542D01*
G01X24088Y75158D02*
X4088D01*
Y85158D01*
X24088D01*
Y75158D01*
G01X4195Y69262D02*
X4387Y68952D01*
X4617Y68745D01*
X4885Y68642D01*
X5192Y68745D01*
X5422Y68952D01*
X5652Y69262D01*
X5729Y69675D01*
Y71742D01*
G01X7295Y68642D02*
Y71742D01*
X8215D01*
X8522Y71587D01*
X8752Y71225D01*
X8829Y70812D01*
X8752Y70399D01*
X8560Y70089D01*
X8215Y69934D01*
X7295D01*
G01X11622Y68642D02*
Y71742D01*
X10204Y69520D01*
X12120D01*
G01X3334Y101125D02*
X3564Y101435D01*
X3832Y101590D01*
X4139Y101642D01*
X4522Y101539D01*
X4790Y101280D01*
X4867Y100970D01*
X4829Y100660D01*
X4675Y100402D01*
X3909Y99885D01*
X3564Y99524D01*
X3334Y99007D01*
X3257Y98542D01*
X4867D01*
G01X24088Y86958D02*
X4088D01*
Y96958D01*
X24088D01*
Y86958D01*
G01X3632Y161928D02*
X3939Y161670D01*
X4284Y161515D01*
X4590D01*
X4897Y161670D01*
X5127Y161928D01*
X5242Y162290D01*
X5165Y162652D01*
X4974Y162962D01*
X4629Y163168D01*
X4169Y163272D01*
X3900Y163478D01*
X3785Y163840D01*
X3862Y164202D01*
X4054Y164460D01*
X4322Y164615D01*
X4590D01*
X4859Y164512D01*
X5089Y164253D01*
G01X6809Y162807D02*
X7077Y163168D01*
X7307Y163375D01*
X7614Y163478D01*
X7882Y163375D01*
X8074Y163168D01*
X8227Y162858D01*
X8265Y162497D01*
X8227Y162187D01*
X8074Y161877D01*
X7844Y161618D01*
X7575Y161515D01*
X7269Y161618D01*
X7000Y161928D01*
X6847Y162393D01*
X6809Y162910D01*
X6885Y163582D01*
X7000Y163943D01*
X7192Y164305D01*
X7460Y164563D01*
X7729Y164615D01*
X7997Y164512D01*
X8189Y164253D01*
G01X40689Y167123D02*
X2757D01*
G01Y173229D02*
Y203938D01*
X8662Y209843D01*
X35237D01*
X41143Y203938D01*
Y167914D01*
G03X42521Y166536I1378J0D01*
G03X43898Y167914I-1J1378D01*
G01Y178495D01*
G01X16668Y69800D02*
Y72900D01*
X18432Y69800D01*
Y72900D01*
G01X20650Y69800D02*
X20420Y69852D01*
X20190Y70058D01*
X20037Y70420D01*
X19960Y70833D01*
X20037Y71247D01*
X20190Y71608D01*
X20420Y71815D01*
X20650Y71867D01*
X20880Y71815D01*
X21110Y71608D01*
X21263Y71247D01*
X21302Y70833D01*
X21263Y70420D01*
X21110Y70058D01*
X20880Y69852D01*
X20650Y69800D01*
G01X24440Y72900D02*
Y69800D01*
G01Y70265D02*
X24287Y70007D01*
X24057Y69852D01*
X23788Y69800D01*
X23482Y69903D01*
X23252Y70162D01*
X23098Y70472D01*
X23060Y70833D01*
X23098Y71195D01*
X23252Y71505D01*
X23482Y71763D01*
X23788Y71867D01*
X24057Y71815D01*
X24248Y71712D01*
X24440Y71505D01*
G01X26275Y71195D02*
X27502D01*
X27387Y71557D01*
X27195Y71763D01*
X26927Y71867D01*
X26658Y71815D01*
X26428Y71660D01*
X26275Y71298D01*
X26198Y70988D01*
Y70678D01*
X26275Y70368D01*
X26467Y70058D01*
X26697Y69852D01*
X26965Y69800D01*
X27233Y69903D01*
X27502Y70213D01*
G01X33050Y69800D02*
Y72900D01*
X32590Y72280D01*
G01Y69800D02*
X33510D01*
G01X16468Y64900D02*
Y68000D01*
X18232Y64900D01*
Y68000D01*
G01X20450Y64900D02*
X20220Y64952D01*
X19990Y65158D01*
X19837Y65520D01*
X19760Y65933D01*
X19837Y66347D01*
X19990Y66708D01*
X20220Y66915D01*
X20450Y66967D01*
X20680Y66915D01*
X20910Y66708D01*
X21063Y66347D01*
X21102Y65933D01*
X21063Y65520D01*
X20910Y65158D01*
X20680Y64952D01*
X20450Y64900D01*
G01X24240Y68000D02*
Y64900D01*
G01Y65365D02*
X24087Y65107D01*
X23857Y64952D01*
X23588Y64900D01*
X23282Y65003D01*
X23052Y65262D01*
X22898Y65572D01*
X22860Y65933D01*
X22898Y66295D01*
X23052Y66605D01*
X23282Y66863D01*
X23588Y66967D01*
X23857Y66915D01*
X24048Y66812D01*
X24240Y66605D01*
G01X26075Y66295D02*
X27302D01*
X27187Y66657D01*
X26995Y66863D01*
X26727Y66967D01*
X26458Y66915D01*
X26228Y66760D01*
X26075Y66398D01*
X25998Y66088D01*
Y65778D01*
X26075Y65468D01*
X26267Y65158D01*
X26497Y64952D01*
X26765Y64900D01*
X27033Y65003D01*
X27302Y65313D01*
G01X32007Y65520D02*
X32237Y65158D01*
X32543Y64952D01*
X32888Y64900D01*
X33195Y64952D01*
X33502Y65210D01*
X33693Y65520D01*
X33732Y65830D01*
X33655Y66192D01*
X33387Y66450D01*
X33118Y66553D01*
X32773D01*
G01X33118D02*
X33348Y66708D01*
X33540Y66967D01*
X33617Y67277D01*
X33540Y67587D01*
X33348Y67845D01*
X33003Y68000D01*
X32658Y67948D01*
X32313Y67742D01*
G01X25662Y79042D02*
Y82142D01*
X25202Y81522D01*
G01Y79042D02*
X26122D01*
G01X25862Y87242D02*
Y90342D01*
X25402Y89722D01*
G01Y87242D02*
X26322D01*
G01X19029Y155694D02*
Y158794D01*
G01X20639D02*
Y155694D01*
G01Y157244D02*
X19029D01*
G01X22091Y156159D02*
X22321Y155901D01*
X22589Y155746D01*
X22934Y155694D01*
X23279Y155797D01*
X23547Y156004D01*
X23739Y156366D01*
X23777Y156779D01*
X23701Y157192D01*
X23509Y157451D01*
X23241Y157657D01*
X22972Y157709D01*
X22704Y157657D01*
X22359Y157451D01*
X22474Y158794D01*
X23509D01*
G01X54215Y23526D02*
X51115D01*
X51735Y23066D01*
G01X54215D02*
Y23986D01*
G01Y26626D02*
X54163Y26894D01*
X54008Y27201D01*
X53750Y27393D01*
X53388Y27469D01*
X53027Y27393D01*
X52717Y27163D01*
X52562Y26818D01*
Y26434D01*
X52458Y26204D01*
X52200Y26013D01*
X51838Y25936D01*
X51477Y26051D01*
X51218Y26319D01*
X51115Y26626D01*
X51218Y26933D01*
X51477Y27201D01*
X51838Y27316D01*
X52200Y27239D01*
X52458Y27048D01*
X52562Y26818D01*
Y26434D01*
X52717Y26089D01*
X53027Y25859D01*
X53388Y25783D01*
X53750Y25859D01*
X54008Y26051D01*
X54163Y26358D01*
X54215Y26626D01*
G01X37533Y28248D02*
X37133D01*
G01X44132Y148918D02*
X66063D01*
Y28248D01*
X44132D01*
G01X37048D02*
Y148918D01*
X37533D01*
G01X51428Y13463D02*
Y16563D01*
G01X53038D02*
Y13463D01*
G01Y15013D02*
X51428D01*
G01X55256Y13463D02*
X55333Y14135D01*
X55448Y14703D01*
X55601Y15220D01*
X55793Y15788D01*
X56100Y16563D01*
X54566D01*
G01X37048Y82677D02*
X31536D01*
Y94488D01*
X37048D01*
G01X42126Y153751D02*
Y156851D01*
X41666Y156231D01*
G01Y153751D02*
X42586D01*
G01X44383Y154371D02*
X44613Y154009D01*
X44919Y153803D01*
X45264Y153751D01*
X45571Y153803D01*
X45878Y154061D01*
X46069Y154371D01*
X46108Y154681D01*
X46031Y155043D01*
X45763Y155301D01*
X45494Y155404D01*
X45149D01*
G01X45494D02*
X45724Y155559D01*
X45916Y155818D01*
X45993Y156128D01*
X45916Y156438D01*
X45724Y156696D01*
X45379Y156851D01*
X45034Y156799D01*
X44689Y156593D01*
G01X32471Y162528D02*
X32778Y162270D01*
X33123Y162115D01*
X33429D01*
X33736Y162270D01*
X33966Y162528D01*
X34081Y162890D01*
X34004Y163252D01*
X33813Y163562D01*
X33468Y163768D01*
X33008Y163872D01*
X32739Y164078D01*
X32624Y164440D01*
X32701Y164802D01*
X32893Y165060D01*
X33161Y165215D01*
X33429D01*
X33698Y165112D01*
X33928Y164853D01*
G01X36376Y162115D02*
Y165215D01*
X35916Y164595D01*
G01Y162115D02*
X36836D01*
G01X207796Y167123D02*
X44389D01*
G01X44648Y204688D02*
X49804Y209843D01*
X201891D01*
X207796Y203938D01*
Y173229D01*
G01X68574Y40547D02*
X68843Y40288D01*
X69149Y40185D01*
X69456Y40288D01*
X69724Y40598D01*
X69916Y41063D01*
X69993Y41528D01*
Y42097D01*
X69916Y42562D01*
X69724Y42975D01*
X69494Y43182D01*
X69226Y43285D01*
X68919Y43182D01*
X68689Y42975D01*
X68536Y42665D01*
X68459Y42252D01*
X68536Y41890D01*
X68728Y41528D01*
X68958Y41322D01*
X69226Y41270D01*
X69533Y41373D01*
X69763Y41632D01*
X69993Y42097D01*
G01X70424Y70232D02*
X70654Y70542D01*
X70922Y70697D01*
X71229Y70749D01*
X71612Y70646D01*
X71880Y70387D01*
X71957Y70077D01*
X71919Y69767D01*
X71765Y69509D01*
X70999Y68992D01*
X70654Y68631D01*
X70424Y68114D01*
X70347Y67649D01*
X71957D01*
G01X73464Y59744D02*
Y117422D01*
X98268D01*
Y59744D01*
X73464D01*
G01X69729Y118760D02*
X70039Y118952D01*
X70246Y119182D01*
X70349Y119450D01*
X70246Y119757D01*
X70039Y119987D01*
X69729Y120217D01*
X69316Y120294D01*
X67249D01*
G01X67766Y121899D02*
X67456Y122129D01*
X67301Y122397D01*
X67249Y122704D01*
X67352Y123087D01*
X67611Y123355D01*
X67921Y123432D01*
X68231Y123394D01*
X68489Y123240D01*
X69006Y122474D01*
X69367Y122129D01*
X69884Y121899D01*
X70349Y121822D01*
Y123432D01*
G01X67249Y125727D02*
X67352Y125420D01*
X67611Y125190D01*
X67921Y125037D01*
X68334Y124922D01*
X68799Y124884D01*
X69264Y124922D01*
X69677Y125037D01*
X69987Y125190D01*
X70246Y125420D01*
X70349Y125727D01*
X70246Y126034D01*
X69987Y126264D01*
X69677Y126417D01*
X69264Y126532D01*
X68799Y126570D01*
X68334Y126532D01*
X67921Y126417D01*
X67611Y126264D01*
X67352Y126034D01*
X67249Y125727D01*
G01X69866Y138933D02*
Y142033D01*
X69406Y141413D01*
G01Y138933D02*
X70326D01*
G01X57109Y159568D02*
Y162668D01*
X58029D01*
X58336Y162513D01*
X58566Y162151D01*
X58643Y161738D01*
X58566Y161325D01*
X58374Y161015D01*
X58029Y160860D01*
X57109D01*
G01X61436Y159568D02*
Y162668D01*
X60018Y160446D01*
X61934D01*
G01X97252Y55375D02*
Y58475D01*
X96792Y57855D01*
G01Y55375D02*
X97712D01*
G01X98268Y83859D02*
X95709D01*
Y93307D01*
X98268D01*
G01X80594Y119749D02*
Y122849D01*
X80134Y122229D01*
G01Y119749D02*
X81054D01*
G01X82966Y122332D02*
X83196Y122642D01*
X83464Y122797D01*
X83771Y122849D01*
X84154Y122746D01*
X84422Y122487D01*
X84499Y122177D01*
X84461Y121867D01*
X84307Y121609D01*
X83541Y121092D01*
X83196Y120731D01*
X82966Y120214D01*
X82889Y119749D01*
X84499D01*
G01X93094Y119425D02*
Y122525D01*
X92634Y121905D01*
G01Y119425D02*
X93554D01*
G01X96194D02*
Y122525D01*
X95734Y121905D01*
G01Y119425D02*
X96654D01*
G01X103794Y50095D02*
X100694D01*
Y51054D01*
X100849Y51360D01*
X101056Y51552D01*
X101469Y51629D01*
X101882Y51552D01*
X102141Y51322D01*
X102296Y51054D01*
Y50095D01*
G01Y51054D02*
X103794Y51629D01*
G01X103174Y53119D02*
X103536Y53349D01*
X103742Y53655D01*
X103794Y54000D01*
X103742Y54307D01*
X103484Y54614D01*
X103174Y54805D01*
X102864Y54844D01*
X102502Y54767D01*
X102244Y54499D01*
X102141Y54230D01*
Y53885D01*
G01Y54230D02*
X101986Y54460D01*
X101727Y54652D01*
X101417Y54729D01*
X101107Y54652D01*
X100849Y54460D01*
X100694Y54115D01*
X100746Y53770D01*
X100952Y53425D01*
G01X103174Y56219D02*
X103536Y56449D01*
X103742Y56755D01*
X103794Y57100D01*
X103742Y57407D01*
X103484Y57714D01*
X103174Y57905D01*
X102864Y57944D01*
X102502Y57867D01*
X102244Y57599D01*
X102141Y57330D01*
Y56985D01*
G01Y57330D02*
X101986Y57560D01*
X101727Y57752D01*
X101417Y57829D01*
X101107Y57752D01*
X100849Y57560D01*
X100694Y57215D01*
X100746Y56870D01*
X100952Y56525D01*
G01X111891Y49983D02*
X108791D01*
Y50942D01*
X108946Y51248D01*
X109153Y51440D01*
X109566Y51517D01*
X109979Y51440D01*
X110238Y51210D01*
X110393Y50942D01*
Y49983D01*
G01Y50942D02*
X111891Y51517D01*
G01Y53850D02*
X111839Y54118D01*
X111684Y54425D01*
X111426Y54617D01*
X111064Y54693D01*
X110703Y54617D01*
X110393Y54387D01*
X110238Y54042D01*
Y53658D01*
X110134Y53428D01*
X109876Y53237D01*
X109514Y53160D01*
X109153Y53275D01*
X108894Y53543D01*
X108791Y53850D01*
X108894Y54157D01*
X109153Y54425D01*
X109514Y54540D01*
X109876Y54463D01*
X110134Y54272D01*
X110238Y54042D01*
Y53658D01*
X110393Y53313D01*
X110703Y53083D01*
X111064Y53007D01*
X111426Y53083D01*
X111684Y53275D01*
X111839Y53582D01*
X111891Y53850D01*
G01X111426Y56107D02*
X111684Y56337D01*
X111839Y56605D01*
X111891Y56950D01*
X111788Y57295D01*
X111581Y57563D01*
X111219Y57755D01*
X110806Y57793D01*
X110393Y57717D01*
X110134Y57525D01*
X109928Y57257D01*
X109876Y56988D01*
X109928Y56720D01*
X110134Y56375D01*
X108791Y56490D01*
Y57525D01*
G01X120591Y49883D02*
X117491D01*
Y50842D01*
X117646Y51148D01*
X117853Y51340D01*
X118266Y51417D01*
X118679Y51340D01*
X118938Y51110D01*
X119093Y50842D01*
Y49883D01*
G01Y50842D02*
X120591Y51417D01*
G01Y53750D02*
X120539Y54018D01*
X120384Y54325D01*
X120126Y54517D01*
X119764Y54593D01*
X119403Y54517D01*
X119093Y54287D01*
X118938Y53942D01*
Y53558D01*
X118834Y53328D01*
X118576Y53137D01*
X118214Y53060D01*
X117853Y53175D01*
X117594Y53443D01*
X117491Y53750D01*
X117594Y54057D01*
X117853Y54325D01*
X118214Y54440D01*
X118576Y54363D01*
X118834Y54172D01*
X118938Y53942D01*
Y53558D01*
X119093Y53213D01*
X119403Y52983D01*
X119764Y52907D01*
X120126Y52983D01*
X120384Y53175D01*
X120539Y53482D01*
X120591Y53750D01*
G01Y56773D02*
X119919Y56850D01*
X119351Y56965D01*
X118834Y57118D01*
X118266Y57310D01*
X117491Y57617D01*
Y56083D01*
G01X116191Y49983D02*
X113091D01*
Y50942D01*
X113246Y51248D01*
X113453Y51440D01*
X113866Y51517D01*
X114279Y51440D01*
X114538Y51210D01*
X114693Y50942D01*
Y49983D01*
G01Y50942D02*
X116191Y51517D01*
G01Y53850D02*
X116139Y54118D01*
X115984Y54425D01*
X115726Y54617D01*
X115364Y54693D01*
X115003Y54617D01*
X114693Y54387D01*
X114538Y54042D01*
Y53658D01*
X114434Y53428D01*
X114176Y53237D01*
X113814Y53160D01*
X113453Y53275D01*
X113194Y53543D01*
X113091Y53850D01*
X113194Y54157D01*
X113453Y54425D01*
X113814Y54540D01*
X114176Y54463D01*
X114434Y54272D01*
X114538Y54042D01*
Y53658D01*
X114693Y53313D01*
X115003Y53083D01*
X115364Y53007D01*
X115726Y53083D01*
X115984Y53275D01*
X116139Y53582D01*
X116191Y53850D01*
G01X115829Y56298D02*
X116088Y56567D01*
X116191Y56873D01*
X116088Y57180D01*
X115778Y57448D01*
X115313Y57640D01*
X114848Y57717D01*
X114279D01*
X113814Y57640D01*
X113401Y57448D01*
X113194Y57218D01*
X113091Y56950D01*
X113194Y56643D01*
X113401Y56413D01*
X113711Y56260D01*
X114124Y56183D01*
X114486Y56260D01*
X114848Y56452D01*
X115054Y56682D01*
X115106Y56950D01*
X115003Y57257D01*
X114744Y57487D01*
X114279Y57717D01*
G01X107891Y49983D02*
X104791D01*
Y50942D01*
X104946Y51248D01*
X105153Y51440D01*
X105566Y51517D01*
X105979Y51440D01*
X106238Y51210D01*
X106393Y50942D01*
Y49983D01*
G01Y50942D02*
X107891Y51517D01*
G01X107529Y53198D02*
X107788Y53467D01*
X107891Y53773D01*
X107788Y54080D01*
X107478Y54348D01*
X107013Y54540D01*
X106548Y54617D01*
X105979D01*
X105514Y54540D01*
X105101Y54348D01*
X104894Y54118D01*
X104791Y53850D01*
X104894Y53543D01*
X105101Y53313D01*
X105411Y53160D01*
X105824Y53083D01*
X106186Y53160D01*
X106548Y53352D01*
X106754Y53582D01*
X106806Y53850D01*
X106703Y54157D01*
X106444Y54387D01*
X105979Y54617D01*
G01X107891Y56950D02*
X104791D01*
X105411Y56490D01*
G01X107891D02*
Y57410D01*
G01X103339Y67488D02*
Y61288D01*
X100139D01*
Y67488D01*
X103339D01*
G01X110358Y61400D02*
Y67600D01*
X113558D01*
Y61400D01*
X110358D01*
G01X120358D02*
Y67600D01*
X123558D01*
Y61400D01*
X120358D01*
G01X115358D02*
Y67600D01*
X118558D01*
Y61400D01*
X115358D01*
G01X105358D02*
Y67600D01*
X108558D01*
Y61400D01*
X105358D01*
G01X113558Y80800D02*
Y74600D01*
X110358D01*
Y80800D01*
X113558D01*
G01X123558D02*
Y74600D01*
X120358D01*
Y80800D01*
X123558D01*
G01X118558D02*
Y74600D01*
X115358D01*
Y80800D01*
X118558D01*
G01X108558D02*
Y74600D01*
X105358D01*
Y80800D01*
X108558D01*
G01X101663Y72784D02*
X101973Y72976D01*
X102180Y73206D01*
X102283Y73474D01*
X102180Y73781D01*
X101973Y74011D01*
X101663Y74241D01*
X101250Y74318D01*
X99183D01*
G01X99700Y75923D02*
X99390Y76153D01*
X99235Y76421D01*
X99183Y76728D01*
X99286Y77111D01*
X99545Y77379D01*
X99855Y77456D01*
X100165Y77418D01*
X100423Y77264D01*
X100940Y76498D01*
X101301Y76153D01*
X101818Y75923D01*
X102283Y75846D01*
Y77456D01*
G01Y79751D02*
X99183D01*
X99803Y79291D01*
G01X102283D02*
Y80211D01*
G01X101034Y93825D02*
X101264Y94135D01*
X101532Y94290D01*
X101839Y94342D01*
X102222Y94239D01*
X102490Y93980D01*
X102567Y93670D01*
X102529Y93360D01*
X102375Y93102D01*
X101609Y92585D01*
X101264Y92224D01*
X101034Y91707D01*
X100957Y91242D01*
X102567D01*
G01X112595Y84062D02*
X112787Y83752D01*
X113017Y83545D01*
X113285Y83442D01*
X113592Y83545D01*
X113822Y83752D01*
X114052Y84062D01*
X114129Y84475D01*
Y86542D01*
G01X115695Y83442D02*
Y86542D01*
X116615D01*
X116922Y86387D01*
X117152Y86025D01*
X117229Y85612D01*
X117152Y85199D01*
X116960Y84889D01*
X116615Y84734D01*
X115695D01*
G01X119485Y83442D02*
X119562Y84114D01*
X119677Y84682D01*
X119830Y85199D01*
X120022Y85767D01*
X120329Y86542D01*
X118795D01*
G01X124288Y87458D02*
X104288D01*
Y97458D01*
X124288D01*
Y87458D01*
G01Y98958D02*
X104288D01*
Y108958D01*
X124288D01*
Y98958D01*
G01X101434Y104825D02*
X101664Y105135D01*
X101932Y105290D01*
X102239Y105342D01*
X102622Y105239D01*
X102890Y104980D01*
X102967Y104670D01*
X102929Y104360D01*
X102775Y104102D01*
X102009Y103585D01*
X101664Y103224D01*
X101434Y102707D01*
X101357Y102242D01*
X102967D01*
G01X116595Y111962D02*
X116787Y111652D01*
X117017Y111445D01*
X117285Y111342D01*
X117592Y111445D01*
X117822Y111652D01*
X118052Y111962D01*
X118129Y112375D01*
Y114442D01*
G01X119695Y111342D02*
Y114442D01*
X120615D01*
X120922Y114287D01*
X121152Y113925D01*
X121229Y113512D01*
X121152Y113099D01*
X120960Y112789D01*
X120615Y112634D01*
X119695D01*
G01X122719Y111962D02*
X122949Y111600D01*
X123255Y111394D01*
X123600Y111342D01*
X123907Y111394D01*
X124214Y111652D01*
X124405Y111962D01*
X124444Y112272D01*
X124367Y112634D01*
X124099Y112892D01*
X123830Y112995D01*
X123485D01*
G01X123830D02*
X124060Y113150D01*
X124252Y113409D01*
X124329Y113719D01*
X124252Y114029D01*
X124060Y114287D01*
X123715Y114442D01*
X123370Y114390D01*
X123025Y114184D01*
G01X111494Y163136D02*
X111686Y162826D01*
X111916Y162619D01*
X112184Y162516D01*
X112491Y162619D01*
X112721Y162826D01*
X112951Y163136D01*
X113028Y163549D01*
Y165616D01*
G01X115361Y162516D02*
Y165616D01*
X114901Y164996D01*
G01Y162516D02*
X115821D01*
G01X117809Y162878D02*
X118078Y162619D01*
X118384Y162516D01*
X118691Y162619D01*
X118959Y162929D01*
X119151Y163394D01*
X119228Y163859D01*
Y164428D01*
X119151Y164893D01*
X118959Y165306D01*
X118729Y165513D01*
X118461Y165616D01*
X118154Y165513D01*
X117924Y165306D01*
X117771Y164996D01*
X117694Y164583D01*
X117771Y164221D01*
X117963Y163859D01*
X118193Y163653D01*
X118461Y163601D01*
X118768Y163704D01*
X118998Y163963D01*
X119228Y164428D01*
G01X133475Y74483D02*
X130375D01*
Y75442D01*
X130530Y75748D01*
X130737Y75940D01*
X131150Y76017D01*
X131563Y75940D01*
X131822Y75710D01*
X131977Y75442D01*
Y74483D01*
G01Y75442D02*
X133475Y76017D01*
G01Y78350D02*
X133423Y78618D01*
X133268Y78925D01*
X133010Y79117D01*
X132648Y79193D01*
X132287Y79117D01*
X131977Y78887D01*
X131822Y78542D01*
Y78158D01*
X131718Y77928D01*
X131460Y77737D01*
X131098Y77660D01*
X130737Y77775D01*
X130478Y78043D01*
X130375Y78350D01*
X130478Y78657D01*
X130737Y78925D01*
X131098Y79040D01*
X131460Y78963D01*
X131718Y78772D01*
X131822Y78542D01*
Y78158D01*
X131977Y77813D01*
X132287Y77583D01*
X132648Y77507D01*
X133010Y77583D01*
X133268Y77775D01*
X133423Y78082D01*
X133475Y78350D01*
G01Y81910D02*
X130375D01*
X132597Y80492D01*
Y82408D01*
G01X141975Y74483D02*
X138875D01*
Y75442D01*
X139030Y75748D01*
X139237Y75940D01*
X139650Y76017D01*
X140063Y75940D01*
X140322Y75710D01*
X140477Y75442D01*
Y74483D01*
G01Y75442D02*
X141975Y76017D01*
G01Y78350D02*
X141923Y78618D01*
X141768Y78925D01*
X141510Y79117D01*
X141148Y79193D01*
X140787Y79117D01*
X140477Y78887D01*
X140322Y78542D01*
Y78158D01*
X140218Y77928D01*
X139960Y77737D01*
X139598Y77660D01*
X139237Y77775D01*
X138978Y78043D01*
X138875Y78350D01*
X138978Y78657D01*
X139237Y78925D01*
X139598Y79040D01*
X139960Y78963D01*
X140218Y78772D01*
X140322Y78542D01*
Y78158D01*
X140477Y77813D01*
X140787Y77583D01*
X141148Y77507D01*
X141510Y77583D01*
X141768Y77775D01*
X141923Y78082D01*
X141975Y78350D01*
G01X140683Y80722D02*
X140322Y80990D01*
X140115Y81220D01*
X140012Y81527D01*
X140115Y81795D01*
X140322Y81987D01*
X140632Y82140D01*
X140993Y82178D01*
X141303Y82140D01*
X141613Y81987D01*
X141872Y81757D01*
X141975Y81488D01*
X141872Y81182D01*
X141562Y80913D01*
X141097Y80760D01*
X140580Y80722D01*
X139908Y80798D01*
X139547Y80913D01*
X139185Y81105D01*
X138927Y81373D01*
X138875Y81642D01*
X138978Y81910D01*
X139237Y82102D01*
G01X137675Y74483D02*
X134575D01*
Y75442D01*
X134730Y75748D01*
X134937Y75940D01*
X135350Y76017D01*
X135763Y75940D01*
X136022Y75710D01*
X136177Y75442D01*
Y74483D01*
G01Y75442D02*
X137675Y76017D01*
G01Y78350D02*
X137623Y78618D01*
X137468Y78925D01*
X137210Y79117D01*
X136848Y79193D01*
X136487Y79117D01*
X136177Y78887D01*
X136022Y78542D01*
Y78158D01*
X135918Y77928D01*
X135660Y77737D01*
X135298Y77660D01*
X134937Y77775D01*
X134678Y78043D01*
X134575Y78350D01*
X134678Y78657D01*
X134937Y78925D01*
X135298Y79040D01*
X135660Y78963D01*
X135918Y78772D01*
X136022Y78542D01*
Y78158D01*
X136177Y77813D01*
X136487Y77583D01*
X136848Y77507D01*
X137210Y77583D01*
X137468Y77775D01*
X137623Y78082D01*
X137675Y78350D01*
G01Y81450D02*
X137623Y81718D01*
X137468Y82025D01*
X137210Y82217D01*
X136848Y82293D01*
X136487Y82217D01*
X136177Y81987D01*
X136022Y81642D01*
Y81258D01*
X135918Y81028D01*
X135660Y80837D01*
X135298Y80760D01*
X134937Y80875D01*
X134678Y81143D01*
X134575Y81450D01*
X134678Y81757D01*
X134937Y82025D01*
X135298Y82140D01*
X135660Y82063D01*
X135918Y81872D01*
X136022Y81642D01*
Y81258D01*
X136177Y80913D01*
X136487Y80683D01*
X136848Y80607D01*
X137210Y80683D01*
X137468Y80875D01*
X137623Y81182D01*
X137675Y81450D01*
G01X129475Y74583D02*
X126375D01*
Y75542D01*
X126530Y75848D01*
X126737Y76040D01*
X127150Y76117D01*
X127563Y76040D01*
X127822Y75810D01*
X127977Y75542D01*
Y74583D01*
G01Y75542D02*
X129475Y76117D01*
G01X129113Y77798D02*
X129372Y78067D01*
X129475Y78373D01*
X129372Y78680D01*
X129062Y78948D01*
X128597Y79140D01*
X128132Y79217D01*
X127563D01*
X127098Y79140D01*
X126685Y78948D01*
X126478Y78718D01*
X126375Y78450D01*
X126478Y78143D01*
X126685Y77913D01*
X126995Y77760D01*
X127408Y77683D01*
X127770Y77760D01*
X128132Y77952D01*
X128338Y78182D01*
X128390Y78450D01*
X128287Y78757D01*
X128028Y78987D01*
X127563Y79217D01*
G01X126375Y81550D02*
X126478Y81243D01*
X126737Y81013D01*
X127047Y80860D01*
X127460Y80745D01*
X127925Y80707D01*
X128390Y80745D01*
X128803Y80860D01*
X129113Y81013D01*
X129372Y81243D01*
X129475Y81550D01*
X129372Y81857D01*
X129113Y82087D01*
X128803Y82240D01*
X128390Y82355D01*
X127925Y82393D01*
X127460Y82355D01*
X127047Y82240D01*
X126737Y82087D01*
X126478Y81857D01*
X126375Y81550D01*
G01X135468Y92000D02*
Y95100D01*
X137232Y92000D01*
Y95100D01*
G01X139450Y92000D02*
X139220Y92052D01*
X138990Y92258D01*
X138837Y92620D01*
X138760Y93033D01*
X138837Y93447D01*
X138990Y93808D01*
X139220Y94015D01*
X139450Y94067D01*
X139680Y94015D01*
X139910Y93808D01*
X140063Y93447D01*
X140102Y93033D01*
X140063Y92620D01*
X139910Y92258D01*
X139680Y92052D01*
X139450Y92000D01*
G01X143240Y95100D02*
Y92000D01*
G01Y92465D02*
X143087Y92207D01*
X142857Y92052D01*
X142588Y92000D01*
X142282Y92103D01*
X142052Y92362D01*
X141898Y92672D01*
X141860Y93033D01*
X141898Y93395D01*
X142052Y93705D01*
X142282Y93963D01*
X142588Y94067D01*
X142857Y94015D01*
X143048Y93912D01*
X143240Y93705D01*
G01X145075Y93395D02*
X146302D01*
X146187Y93757D01*
X145995Y93963D01*
X145727Y94067D01*
X145458Y94015D01*
X145228Y93860D01*
X145075Y93498D01*
X144998Y93188D01*
Y92878D01*
X145075Y92568D01*
X145267Y92258D01*
X145497Y92052D01*
X145765Y92000D01*
X146033Y92103D01*
X146302Y92413D01*
G01X152310Y92000D02*
Y95100D01*
X150892Y92878D01*
X152808D01*
G01X126562Y87542D02*
Y90642D01*
X126102Y90022D01*
G01Y87542D02*
X127022D01*
G01X135168Y100700D02*
Y103800D01*
X136932Y100700D01*
Y103800D01*
G01X139150Y100700D02*
X138920Y100752D01*
X138690Y100958D01*
X138537Y101320D01*
X138460Y101733D01*
X138537Y102147D01*
X138690Y102508D01*
X138920Y102715D01*
X139150Y102767D01*
X139380Y102715D01*
X139610Y102508D01*
X139763Y102147D01*
X139802Y101733D01*
X139763Y101320D01*
X139610Y100958D01*
X139380Y100752D01*
X139150Y100700D01*
G01X142940Y103800D02*
Y100700D01*
G01Y101165D02*
X142787Y100907D01*
X142557Y100752D01*
X142288Y100700D01*
X141982Y100803D01*
X141752Y101062D01*
X141598Y101372D01*
X141560Y101733D01*
X141598Y102095D01*
X141752Y102405D01*
X141982Y102663D01*
X142288Y102767D01*
X142557Y102715D01*
X142748Y102612D01*
X142940Y102405D01*
G01X144775Y102095D02*
X146002D01*
X145887Y102457D01*
X145695Y102663D01*
X145427Y102767D01*
X145158Y102715D01*
X144928Y102560D01*
X144775Y102198D01*
X144698Y101888D01*
Y101578D01*
X144775Y101268D01*
X144967Y100958D01*
X145197Y100752D01*
X145465Y100700D01*
X145733Y100803D01*
X146002Y101113D01*
G01X150822Y103283D02*
X151052Y103593D01*
X151320Y103748D01*
X151627Y103800D01*
X152010Y103697D01*
X152278Y103438D01*
X152355Y103128D01*
X152317Y102818D01*
X152163Y102560D01*
X151397Y102043D01*
X151052Y101682D01*
X150822Y101165D01*
X150745Y100700D01*
X152355D01*
G01X125962Y102342D02*
Y105442D01*
X125502Y104822D01*
G01Y102342D02*
X126422D01*
G01X181342Y158872D02*
Y161972D01*
X182262D01*
X182569Y161817D01*
X182799Y161455D01*
X182876Y161042D01*
X182799Y160629D01*
X182607Y160319D01*
X182262Y160164D01*
X181342D01*
G01X185209Y158872D02*
Y161972D01*
X184749Y161352D01*
G01Y158872D02*
X185669D01*
G01X219700Y88800D02*
X280000D01*
Y59100D01*
X217100D01*
Y88800D01*
X219700D01*
G01X220743Y65782D02*
Y68882D01*
X221702D01*
X222008Y68727D01*
X222200Y68520D01*
X222277Y68107D01*
X222200Y67694D01*
X221970Y67435D01*
X221702Y67280D01*
X220743D01*
G01X221702D02*
X222277Y65782D01*
G01X223882Y68365D02*
X224112Y68675D01*
X224380Y68830D01*
X224687Y68882D01*
X225070Y68779D01*
X225338Y68520D01*
X225415Y68210D01*
X225377Y67900D01*
X225223Y67642D01*
X224457Y67125D01*
X224112Y66764D01*
X223882Y66247D01*
X223805Y65782D01*
X225415D01*
G01X220743Y70082D02*
Y73182D01*
X221702D01*
X222008Y73027D01*
X222200Y72820D01*
X222277Y72407D01*
X222200Y71994D01*
X221970Y71735D01*
X221702Y71580D01*
X220743D01*
G01X221702D02*
X222277Y70082D01*
G01X223882Y71374D02*
X224150Y71735D01*
X224380Y71942D01*
X224687Y72045D01*
X224955Y71942D01*
X225147Y71735D01*
X225300Y71425D01*
X225338Y71064D01*
X225300Y70754D01*
X225147Y70444D01*
X224917Y70185D01*
X224648Y70082D01*
X224342Y70185D01*
X224073Y70495D01*
X223920Y70960D01*
X223882Y71477D01*
X223958Y72149D01*
X224073Y72510D01*
X224265Y72872D01*
X224533Y73130D01*
X224802Y73182D01*
X225070Y73079D01*
X225262Y72820D01*
G01X220743Y74382D02*
Y77482D01*
X221702D01*
X222008Y77327D01*
X222200Y77120D01*
X222277Y76707D01*
X222200Y76294D01*
X221970Y76035D01*
X221702Y75880D01*
X220743D01*
G01X221702D02*
X222277Y74382D01*
G01X224610D02*
X224878Y74434D01*
X225185Y74589D01*
X225377Y74847D01*
X225453Y75209D01*
X225377Y75570D01*
X225147Y75880D01*
X224802Y76035D01*
X224418D01*
X224188Y76139D01*
X223997Y76397D01*
X223920Y76759D01*
X224035Y77120D01*
X224303Y77379D01*
X224610Y77482D01*
X224917Y77379D01*
X225185Y77120D01*
X225300Y76759D01*
X225223Y76397D01*
X225032Y76139D01*
X224802Y76035D01*
X224418D01*
X224073Y75880D01*
X223843Y75570D01*
X223767Y75209D01*
X223843Y74847D01*
X224035Y74589D01*
X224342Y74434D01*
X224610Y74382D01*
G01X220743Y61982D02*
Y65082D01*
X221702D01*
X222008Y64927D01*
X222200Y64720D01*
X222277Y64307D01*
X222200Y63894D01*
X221970Y63635D01*
X221702Y63480D01*
X220743D01*
G01X221702D02*
X222277Y61982D01*
G01X225070D02*
Y65082D01*
X223652Y62860D01*
X225568D01*
G01X226982Y63274D02*
X227250Y63635D01*
X227480Y63842D01*
X227787Y63945D01*
X228055Y63842D01*
X228247Y63635D01*
X228400Y63325D01*
X228438Y62964D01*
X228400Y62654D01*
X228247Y62344D01*
X228017Y62085D01*
X227748Y61982D01*
X227442Y62085D01*
X227173Y62395D01*
X227020Y62860D01*
X226982Y63377D01*
X227058Y64049D01*
X227173Y64410D01*
X227365Y64772D01*
X227633Y65030D01*
X227902Y65082D01*
X228170Y64979D01*
X228362Y64720D01*
G01X234050Y69525D02*
Y72625D01*
X235009D01*
X235315Y72470D01*
X235507Y72263D01*
X235584Y71850D01*
X235507Y71437D01*
X235277Y71178D01*
X235009Y71023D01*
X234050D01*
G01X235009D02*
X235584Y69525D01*
G01X237074Y69990D02*
X237304Y69732D01*
X237572Y69577D01*
X237917Y69525D01*
X238262Y69628D01*
X238530Y69835D01*
X238722Y70197D01*
X238760Y70610D01*
X238684Y71023D01*
X238492Y71282D01*
X238224Y71488D01*
X237955Y71540D01*
X237687Y71488D01*
X237342Y71282D01*
X237457Y72625D01*
X238492D01*
G01X240365Y69887D02*
X240634Y69628D01*
X240940Y69525D01*
X241247Y69628D01*
X241515Y69938D01*
X241707Y70403D01*
X241784Y70868D01*
Y71437D01*
X241707Y71902D01*
X241515Y72315D01*
X241285Y72522D01*
X241017Y72625D01*
X240710Y72522D01*
X240480Y72315D01*
X240327Y72005D01*
X240250Y71592D01*
X240327Y71230D01*
X240519Y70868D01*
X240749Y70662D01*
X241017Y70610D01*
X241324Y70713D01*
X241554Y70972D01*
X241784Y71437D01*
G01X231471Y65709D02*
Y68809D01*
X232430D01*
X232736Y68654D01*
X232928Y68447D01*
X233005Y68034D01*
X232928Y67621D01*
X232698Y67362D01*
X232430Y67207D01*
X231471D01*
G01X232430D02*
X233005Y65709D01*
G01X234610Y67001D02*
X234878Y67362D01*
X235108Y67569D01*
X235415Y67672D01*
X235683Y67569D01*
X235875Y67362D01*
X236028Y67052D01*
X236066Y66691D01*
X236028Y66381D01*
X235875Y66071D01*
X235645Y65812D01*
X235376Y65709D01*
X235070Y65812D01*
X234801Y66122D01*
X234648Y66587D01*
X234610Y67104D01*
X234686Y67776D01*
X234801Y68137D01*
X234993Y68499D01*
X235261Y68757D01*
X235530Y68809D01*
X235798Y68706D01*
X235990Y68447D01*
G01X238438Y65709D02*
X238706Y65761D01*
X239013Y65916D01*
X239205Y66174D01*
X239281Y66536D01*
X239205Y66897D01*
X238975Y67207D01*
X238630Y67362D01*
X238246D01*
X238016Y67466D01*
X237825Y67724D01*
X237748Y68086D01*
X237863Y68447D01*
X238131Y68706D01*
X238438Y68809D01*
X238745Y68706D01*
X239013Y68447D01*
X239128Y68086D01*
X239051Y67724D01*
X238860Y67466D01*
X238630Y67362D01*
X238246D01*
X237901Y67207D01*
X237671Y66897D01*
X237595Y66536D01*
X237671Y66174D01*
X237863Y65916D01*
X238170Y65761D01*
X238438Y65709D01*
G01X231471Y61709D02*
Y64809D01*
X232430D01*
X232736Y64654D01*
X232928Y64447D01*
X233005Y64034D01*
X232928Y63621D01*
X232698Y63362D01*
X232430Y63207D01*
X231471D01*
G01X232430D02*
X233005Y61709D01*
G01X234610Y63001D02*
X234878Y63362D01*
X235108Y63569D01*
X235415Y63672D01*
X235683Y63569D01*
X235875Y63362D01*
X236028Y63052D01*
X236066Y62691D01*
X236028Y62381D01*
X235875Y62071D01*
X235645Y61812D01*
X235376Y61709D01*
X235070Y61812D01*
X234801Y62122D01*
X234648Y62587D01*
X234610Y63104D01*
X234686Y63776D01*
X234801Y64137D01*
X234993Y64499D01*
X235261Y64757D01*
X235530Y64809D01*
X235798Y64706D01*
X235990Y64447D01*
G01X237786Y62071D02*
X238055Y61812D01*
X238361Y61709D01*
X238668Y61812D01*
X238936Y62122D01*
X239128Y62587D01*
X239205Y63052D01*
Y63621D01*
X239128Y64086D01*
X238936Y64499D01*
X238706Y64706D01*
X238438Y64809D01*
X238131Y64706D01*
X237901Y64499D01*
X237748Y64189D01*
X237671Y63776D01*
X237748Y63414D01*
X237940Y63052D01*
X238170Y62846D01*
X238438Y62794D01*
X238745Y62897D01*
X238975Y63156D01*
X239205Y63621D01*
G01X235800Y88700D02*
Y80800D01*
X246100D01*
Y88700D01*
G01X220743Y82982D02*
Y86082D01*
X221702D01*
X222008Y85927D01*
X222200Y85720D01*
X222277Y85307D01*
X222200Y84894D01*
X221970Y84635D01*
X221702Y84480D01*
X220743D01*
G01X221702D02*
X222277Y82982D01*
G01X224610D02*
Y86082D01*
X224150Y85462D01*
G01Y82982D02*
X225070D01*
G01X228170D02*
Y86082D01*
X226752Y83860D01*
X228668D01*
G01X220743Y78682D02*
Y81782D01*
X221702D01*
X222008Y81627D01*
X222200Y81420D01*
X222277Y81007D01*
X222200Y80594D01*
X221970Y80335D01*
X221702Y80180D01*
X220743D01*
G01X221702D02*
X222277Y78682D01*
G01X224610D02*
Y81782D01*
X224150Y81162D01*
G01Y78682D02*
X225070D01*
G01X227710Y81782D02*
X227403Y81679D01*
X227173Y81420D01*
X227020Y81110D01*
X226905Y80697D01*
X226867Y80232D01*
X226905Y79767D01*
X227020Y79354D01*
X227173Y79044D01*
X227403Y78785D01*
X227710Y78682D01*
X228017Y78785D01*
X228247Y79044D01*
X228400Y79354D01*
X228515Y79767D01*
X228553Y80232D01*
X228515Y80697D01*
X228400Y81110D01*
X228247Y81420D01*
X228017Y81679D01*
X227710Y81782D01*
G01X231383Y109300D02*
Y115600D01*
X233263D01*
X233890Y115285D01*
X234360Y114550D01*
X234517Y113710D01*
X234360Y112870D01*
X233968Y112240D01*
X233263Y111925D01*
X231383D01*
G01X239250Y109300D02*
X238623Y109405D01*
X238075Y109825D01*
X237605Y110455D01*
X237292Y111190D01*
X237135Y112030D01*
Y112870D01*
X237292Y113710D01*
X237605Y114445D01*
X238075Y115075D01*
X238623Y115495D01*
X239250Y115600D01*
X239877Y115495D01*
X240425Y115075D01*
X240895Y114445D01*
X241208Y113710D01*
X241365Y112870D01*
Y112030D01*
X241208Y111190D01*
X240895Y110455D01*
X240425Y109825D01*
X239877Y109405D01*
X239250Y109300D01*
G01X243200Y115600D02*
X244297Y109300D01*
X245550Y115600D01*
X246803Y109300D01*
X247900Y115600D01*
G01X253417Y109300D02*
X250283D01*
Y115600D01*
X253417D01*
G01X252163Y112555D02*
X250283D01*
G01X256583Y109300D02*
Y115600D01*
X258542D01*
X259168Y115285D01*
X259560Y114865D01*
X259717Y114025D01*
X259560Y113185D01*
X259090Y112660D01*
X258542Y112345D01*
X256583D01*
G01X258542D02*
X259717Y109300D01*
G01X272473Y115075D02*
X272003Y115390D01*
X271455Y115600D01*
X270828D01*
X270123Y115285D01*
X269575Y114760D01*
X269183Y114130D01*
X268870Y113080D01*
X268792Y112135D01*
X268948Y111190D01*
X269183Y110560D01*
X269653Y109930D01*
X270202Y109510D01*
X270750Y109300D01*
X271298D01*
X271847Y109510D01*
X272317Y109825D01*
X272708Y110245D01*
G01X277050Y109300D02*
X276423Y109405D01*
X275875Y109825D01*
X275405Y110455D01*
X275092Y111190D01*
X274935Y112030D01*
Y112870D01*
X275092Y113710D01*
X275405Y114445D01*
X275875Y115075D01*
X276423Y115495D01*
X277050Y115600D01*
X277677Y115495D01*
X278225Y115075D01*
X278695Y114445D01*
X279008Y113710D01*
X279165Y112870D01*
Y112030D01*
X279008Y111190D01*
X278695Y110455D01*
X278225Y109825D01*
X277677Y109405D01*
X277050Y109300D01*
G01X281548D02*
Y115600D01*
X285152Y109300D01*
Y115600D01*
G01X287848Y109300D02*
Y115600D01*
X291452Y109300D01*
Y115600D01*
G01X259859Y61716D02*
X256759D01*
Y62675D01*
X256914Y62981D01*
X257121Y63173D01*
X257534Y63250D01*
X257947Y63173D01*
X258206Y62943D01*
X258361Y62675D01*
Y61716D01*
G01Y62675D02*
X259859Y63250D01*
G01X259239Y64740D02*
X259601Y64970D01*
X259807Y65276D01*
X259859Y65621D01*
X259807Y65928D01*
X259549Y66235D01*
X259239Y66426D01*
X258929Y66465D01*
X258567Y66388D01*
X258309Y66120D01*
X258206Y65851D01*
Y65506D01*
G01Y65851D02*
X258051Y66081D01*
X257792Y66273D01*
X257482Y66350D01*
X257172Y66273D01*
X256914Y66081D01*
X256759Y65736D01*
X256811Y65391D01*
X257017Y65046D01*
G01X259497Y68031D02*
X259756Y68300D01*
X259859Y68606D01*
X259756Y68913D01*
X259446Y69181D01*
X258981Y69373D01*
X258516Y69450D01*
X257947D01*
X257482Y69373D01*
X257069Y69181D01*
X256862Y68951D01*
X256759Y68683D01*
X256862Y68376D01*
X257069Y68146D01*
X257379Y67993D01*
X257792Y67916D01*
X258154Y67993D01*
X258516Y68185D01*
X258722Y68415D01*
X258774Y68683D01*
X258671Y68990D01*
X258412Y69220D01*
X257947Y69450D01*
G01X244363Y60536D02*
X241263D01*
Y61495D01*
X241418Y61801D01*
X241625Y61993D01*
X242038Y62070D01*
X242451Y61993D01*
X242710Y61763D01*
X242865Y61495D01*
Y60536D01*
G01Y61495D02*
X244363Y62070D01*
G01X243743Y63560D02*
X244105Y63790D01*
X244311Y64096D01*
X244363Y64441D01*
X244311Y64748D01*
X244053Y65055D01*
X243743Y65246D01*
X243433Y65285D01*
X243071Y65208D01*
X242813Y64940D01*
X242710Y64671D01*
Y64326D01*
G01Y64671D02*
X242555Y64901D01*
X242296Y65093D01*
X241986Y65170D01*
X241676Y65093D01*
X241418Y64901D01*
X241263Y64556D01*
X241315Y64211D01*
X241521Y63866D01*
G01X244363Y67963D02*
X241263D01*
X243485Y66545D01*
Y68461D01*
G01X249575Y61750D02*
X246475D01*
Y62709D01*
X246630Y63015D01*
X246837Y63207D01*
X247250Y63284D01*
X247663Y63207D01*
X247922Y62977D01*
X248077Y62709D01*
Y61750D01*
G01Y62709D02*
X249575Y63284D01*
G01X249110Y64774D02*
X249368Y65004D01*
X249523Y65272D01*
X249575Y65617D01*
X249472Y65962D01*
X249265Y66230D01*
X248903Y66422D01*
X248490Y66460D01*
X248077Y66384D01*
X247818Y66192D01*
X247612Y65924D01*
X247560Y65655D01*
X247612Y65387D01*
X247818Y65042D01*
X246475Y65157D01*
Y66192D01*
G01X249575Y68640D02*
X248903Y68717D01*
X248335Y68832D01*
X247818Y68985D01*
X247250Y69177D01*
X246475Y69484D01*
Y67950D01*
G01X253591Y61916D02*
X250491D01*
Y62875D01*
X250646Y63181D01*
X250853Y63373D01*
X251266Y63450D01*
X251679Y63373D01*
X251938Y63143D01*
X252093Y62875D01*
Y61916D01*
G01Y62875D02*
X253591Y63450D01*
G01X253126Y64940D02*
X253384Y65170D01*
X253539Y65438D01*
X253591Y65783D01*
X253488Y66128D01*
X253281Y66396D01*
X252919Y66588D01*
X252506Y66626D01*
X252093Y66550D01*
X251834Y66358D01*
X251628Y66090D01*
X251576Y65821D01*
X251628Y65553D01*
X251834Y65208D01*
X250491Y65323D01*
Y66358D01*
G01X252299Y68155D02*
X251938Y68423D01*
X251731Y68653D01*
X251628Y68960D01*
X251731Y69228D01*
X251938Y69420D01*
X252248Y69573D01*
X252609Y69611D01*
X252919Y69573D01*
X253229Y69420D01*
X253488Y69190D01*
X253591Y68921D01*
X253488Y68615D01*
X253178Y68346D01*
X252713Y68193D01*
X252196Y68155D01*
X251524Y68231D01*
X251163Y68346D01*
X250801Y68538D01*
X250543Y68806D01*
X250491Y69075D01*
X250594Y69343D01*
X250853Y69535D01*
G01X240092Y83100D02*
X241050Y86200D01*
X242008Y83100D01*
G01X241663Y84185D02*
X240437D01*
G01X284176Y40609D02*
Y43709D01*
X283716Y43089D01*
G01Y40609D02*
X284636D01*
G01X269371Y69906D02*
Y73006D01*
X270330D01*
X270636Y72851D01*
X270828Y72644D01*
X270905Y72231D01*
X270828Y71818D01*
X270598Y71559D01*
X270330Y71404D01*
X269371D01*
G01X270330D02*
X270905Y69906D01*
G01X273238D02*
Y73006D01*
X272778Y72386D01*
G01Y69906D02*
X273698D01*
G01X275495Y70526D02*
X275725Y70164D01*
X276031Y69958D01*
X276376Y69906D01*
X276683Y69958D01*
X276990Y70216D01*
X277181Y70526D01*
X277220Y70836D01*
X277143Y71198D01*
X276875Y71456D01*
X276606Y71559D01*
X276261D01*
G01X276606D02*
X276836Y71714D01*
X277028Y71973D01*
X277105Y72283D01*
X277028Y72593D01*
X276836Y72851D01*
X276491Y73006D01*
X276146Y72954D01*
X275801Y72748D01*
G01X269471Y74706D02*
Y77806D01*
X270430D01*
X270736Y77651D01*
X270928Y77444D01*
X271005Y77031D01*
X270928Y76618D01*
X270698Y76359D01*
X270430Y76204D01*
X269471D01*
G01X270430D02*
X271005Y74706D01*
G01X272686Y75068D02*
X272955Y74809D01*
X273261Y74706D01*
X273568Y74809D01*
X273836Y75119D01*
X274028Y75584D01*
X274105Y76049D01*
Y76618D01*
X274028Y77083D01*
X273836Y77496D01*
X273606Y77703D01*
X273338Y77806D01*
X273031Y77703D01*
X272801Y77496D01*
X272648Y77186D01*
X272571Y76773D01*
X272648Y76411D01*
X272840Y76049D01*
X273070Y75843D01*
X273338Y75791D01*
X273645Y75894D01*
X273875Y76153D01*
X274105Y76618D01*
G01X263891Y61716D02*
X260791D01*
Y62675D01*
X260946Y62981D01*
X261153Y63173D01*
X261566Y63250D01*
X261979Y63173D01*
X262238Y62943D01*
X262393Y62675D01*
Y61716D01*
G01Y62675D02*
X263891Y63250D01*
G01X263271Y64740D02*
X263633Y64970D01*
X263839Y65276D01*
X263891Y65621D01*
X263839Y65928D01*
X263581Y66235D01*
X263271Y66426D01*
X262961Y66465D01*
X262599Y66388D01*
X262341Y66120D01*
X262238Y65851D01*
Y65506D01*
G01Y65851D02*
X262083Y66081D01*
X261824Y66273D01*
X261514Y66350D01*
X261204Y66273D01*
X260946Y66081D01*
X260791Y65736D01*
X260843Y65391D01*
X261049Y65046D01*
G01X263891Y68683D02*
X263839Y68951D01*
X263684Y69258D01*
X263426Y69450D01*
X263064Y69526D01*
X262703Y69450D01*
X262393Y69220D01*
X262238Y68875D01*
Y68491D01*
X262134Y68261D01*
X261876Y68070D01*
X261514Y67993D01*
X261153Y68108D01*
X260894Y68376D01*
X260791Y68683D01*
X260894Y68990D01*
X261153Y69258D01*
X261514Y69373D01*
X261876Y69296D01*
X262134Y69105D01*
X262238Y68875D01*
Y68491D01*
X262393Y68146D01*
X262703Y67916D01*
X263064Y67840D01*
X263426Y67916D01*
X263684Y68108D01*
X263839Y68415D01*
X263891Y68683D01*
G01X268075Y61716D02*
X264975D01*
Y62675D01*
X265130Y62981D01*
X265337Y63173D01*
X265750Y63250D01*
X266163Y63173D01*
X266422Y62943D01*
X266577Y62675D01*
Y61716D01*
G01Y62675D02*
X268075Y63250D01*
G01X267610Y64740D02*
X267868Y64970D01*
X268023Y65238D01*
X268075Y65583D01*
X267972Y65928D01*
X267765Y66196D01*
X267403Y66388D01*
X266990Y66426D01*
X266577Y66350D01*
X266318Y66158D01*
X266112Y65890D01*
X266060Y65621D01*
X266112Y65353D01*
X266318Y65008D01*
X264975Y65123D01*
Y66158D01*
G01X268075Y68683D02*
X268023Y68951D01*
X267868Y69258D01*
X267610Y69450D01*
X267248Y69526D01*
X266887Y69450D01*
X266577Y69220D01*
X266422Y68875D01*
Y68491D01*
X266318Y68261D01*
X266060Y68070D01*
X265698Y67993D01*
X265337Y68108D01*
X265078Y68376D01*
X264975Y68683D01*
X265078Y68990D01*
X265337Y69258D01*
X265698Y69373D01*
X266060Y69296D01*
X266318Y69105D01*
X266422Y68875D01*
Y68491D01*
X266577Y68146D01*
X266887Y67916D01*
X267248Y67840D01*
X267610Y67916D01*
X267868Y68108D01*
X268023Y68415D01*
X268075Y68683D01*
G01X269371Y61609D02*
Y64709D01*
X270330D01*
X270636Y64554D01*
X270828Y64347D01*
X270905Y63934D01*
X270828Y63521D01*
X270598Y63262D01*
X270330Y63107D01*
X269371D01*
G01X270330D02*
X270905Y61609D01*
G01X272510Y62901D02*
X272778Y63262D01*
X273008Y63469D01*
X273315Y63572D01*
X273583Y63469D01*
X273775Y63262D01*
X273928Y62952D01*
X273966Y62591D01*
X273928Y62281D01*
X273775Y61971D01*
X273545Y61712D01*
X273276Y61609D01*
X272970Y61712D01*
X272701Y62022D01*
X272548Y62487D01*
X272510Y63004D01*
X272586Y63676D01*
X272701Y64037D01*
X272893Y64399D01*
X273161Y64657D01*
X273430Y64709D01*
X273698Y64606D01*
X273890Y64347D01*
G01X275610Y62901D02*
X275878Y63262D01*
X276108Y63469D01*
X276415Y63572D01*
X276683Y63469D01*
X276875Y63262D01*
X277028Y62952D01*
X277066Y62591D01*
X277028Y62281D01*
X276875Y61971D01*
X276645Y61712D01*
X276376Y61609D01*
X276070Y61712D01*
X275801Y62022D01*
X275648Y62487D01*
X275610Y63004D01*
X275686Y63676D01*
X275801Y64037D01*
X275993Y64399D01*
X276261Y64657D01*
X276530Y64709D01*
X276798Y64606D01*
X276990Y64347D01*
G01X269371Y65809D02*
Y68909D01*
X270330D01*
X270636Y68754D01*
X270828Y68547D01*
X270905Y68134D01*
X270828Y67721D01*
X270598Y67462D01*
X270330Y67307D01*
X269371D01*
G01X270330D02*
X270905Y65809D01*
G01X272510Y67101D02*
X272778Y67462D01*
X273008Y67669D01*
X273315Y67772D01*
X273583Y67669D01*
X273775Y67462D01*
X273928Y67152D01*
X273966Y66791D01*
X273928Y66481D01*
X273775Y66171D01*
X273545Y65912D01*
X273276Y65809D01*
X272970Y65912D01*
X272701Y66222D01*
X272548Y66687D01*
X272510Y67204D01*
X272586Y67876D01*
X272701Y68237D01*
X272893Y68599D01*
X273161Y68857D01*
X273430Y68909D01*
X273698Y68806D01*
X273890Y68547D01*
G01X276261Y65809D02*
X276338Y66481D01*
X276453Y67049D01*
X276606Y67566D01*
X276798Y68134D01*
X277105Y68909D01*
X275571D01*
G01X269871Y82806D02*
Y85906D01*
X270830D01*
X271136Y85751D01*
X271328Y85544D01*
X271405Y85131D01*
X271328Y84718D01*
X271098Y84459D01*
X270830Y84304D01*
X269871D01*
G01X270830D02*
X271405Y82806D01*
G01X272895Y83271D02*
X273125Y83013D01*
X273393Y82858D01*
X273738Y82806D01*
X274083Y82909D01*
X274351Y83116D01*
X274543Y83478D01*
X274581Y83891D01*
X274505Y84304D01*
X274313Y84563D01*
X274045Y84769D01*
X273776Y84821D01*
X273508Y84769D01*
X273163Y84563D01*
X273278Y85906D01*
X274313D01*
G01X269771Y78706D02*
Y81806D01*
X270730D01*
X271036Y81651D01*
X271228Y81444D01*
X271305Y81031D01*
X271228Y80618D01*
X270998Y80359D01*
X270730Y80204D01*
X269771D01*
G01X270730D02*
X271305Y78706D01*
G01X273561D02*
X273638Y79378D01*
X273753Y79946D01*
X273906Y80463D01*
X274098Y81031D01*
X274405Y81806D01*
X272871D01*
G01X285807Y41850D02*
Y-127559D01*
X327737D01*
Y83189D01*
X285807D01*
Y41850D01*
G01Y-9842D02*
X327737D01*
G01X285855Y85437D02*
X286047Y85127D01*
X286277Y84920D01*
X286545Y84817D01*
X286852Y84920D01*
X287082Y85127D01*
X287312Y85437D01*
X287389Y85850D01*
Y87917D01*
G01X289722Y84817D02*
Y87917D01*
X289262Y87297D01*
G01Y84817D02*
X290182D01*
G01X292822D02*
Y87917D01*
X292362Y87297D01*
G01Y84817D02*
X293282D01*
G01X302632Y143881D02*
Y146981D01*
G01X304242D02*
Y143881D01*
G01Y145431D02*
X302632D01*
G01X305694Y144501D02*
X305924Y144139D01*
X306230Y143933D01*
X306575Y143881D01*
X306882Y143933D01*
X307189Y144191D01*
X307380Y144501D01*
X307419Y144811D01*
X307342Y145173D01*
X307074Y145431D01*
X306805Y145534D01*
X306460D01*
G01X306805D02*
X307035Y145689D01*
X307227Y145948D01*
X307304Y146258D01*
X307227Y146568D01*
X307035Y146826D01*
X306690Y146981D01*
X306345Y146929D01*
X306000Y146723D01*
G01X386792Y-52954D02*
X316516D01*
G01D02*
Y86022D01*
G01X328327Y74212D02*
X374981D01*
Y-41143D01*
X328327D01*
Y74212D01*
G01X321261Y18651D02*
Y21751D01*
X322027D01*
X322334Y21596D01*
X322564Y21389D01*
X322756Y21079D01*
X322909Y20718D01*
X322947Y20201D01*
X322909Y19684D01*
X322756Y19323D01*
X322564Y19013D01*
X322334Y18806D01*
X322027Y18651D01*
X321261D01*
G01X324476Y21234D02*
X324706Y21544D01*
X324974Y21699D01*
X325281Y21751D01*
X325664Y21648D01*
X325932Y21389D01*
X326009Y21079D01*
X325971Y20769D01*
X325817Y20511D01*
X325051Y19994D01*
X324706Y19633D01*
X324476Y19116D01*
X324399Y18651D01*
X326009D01*
G01X321261Y10776D02*
Y13876D01*
X322027D01*
X322334Y13721D01*
X322564Y13514D01*
X322756Y13204D01*
X322909Y12843D01*
X322947Y12326D01*
X322909Y11809D01*
X322756Y11448D01*
X322564Y11138D01*
X322334Y10931D01*
X322027Y10776D01*
X321261D01*
G01X324361Y11396D02*
X324591Y11034D01*
X324897Y10828D01*
X325242Y10776D01*
X325549Y10828D01*
X325856Y11086D01*
X326047Y11396D01*
X326086Y11706D01*
X326009Y12068D01*
X325741Y12326D01*
X325472Y12429D01*
X325127D01*
G01X325472D02*
X325702Y12584D01*
X325894Y12843D01*
X325971Y13153D01*
X325894Y13463D01*
X325702Y13721D01*
X325357Y13876D01*
X325012Y13824D01*
X324667Y13618D01*
G01X321261Y26525D02*
Y29625D01*
X322027D01*
X322334Y29470D01*
X322564Y29263D01*
X322756Y28953D01*
X322909Y28592D01*
X322947Y28075D01*
X322909Y27558D01*
X322756Y27197D01*
X322564Y26887D01*
X322334Y26680D01*
X322027Y26525D01*
X321261D01*
G01X325204D02*
Y29625D01*
X324744Y29005D01*
G01Y26525D02*
X325664D01*
G01X321146Y42273D02*
X322104Y45373D01*
X323062Y42273D01*
G01X322717Y43358D02*
X321491D01*
G01X324361Y42893D02*
X324591Y42531D01*
X324897Y42325D01*
X325242Y42273D01*
X325549Y42325D01*
X325856Y42583D01*
X326047Y42893D01*
X326086Y43203D01*
X326009Y43565D01*
X325741Y43823D01*
X325472Y43926D01*
X325127D01*
G01X325472D02*
X325702Y44081D01*
X325894Y44340D01*
X325971Y44650D01*
X325894Y44960D01*
X325702Y45218D01*
X325357Y45373D01*
X325012Y45321D01*
X324667Y45115D01*
G01X321146Y50147D02*
X322104Y53247D01*
X323062Y50147D01*
G01X322717Y51232D02*
X321491D01*
G01X324476Y52730D02*
X324706Y53040D01*
X324974Y53195D01*
X325281Y53247D01*
X325664Y53144D01*
X325932Y52885D01*
X326009Y52575D01*
X325971Y52265D01*
X325817Y52007D01*
X325051Y51490D01*
X324706Y51129D01*
X324476Y50612D01*
X324399Y50147D01*
X326009D01*
G01X316737Y87987D02*
X316929Y87677D01*
X317159Y87470D01*
X317427Y87367D01*
X317734Y87470D01*
X317964Y87677D01*
X318194Y87987D01*
X318271Y88400D01*
Y90467D01*
G01X319761Y87987D02*
X319991Y87625D01*
X320297Y87419D01*
X320642Y87367D01*
X320949Y87419D01*
X321256Y87677D01*
X321447Y87987D01*
X321486Y88297D01*
X321409Y88659D01*
X321141Y88917D01*
X320872Y89020D01*
X320527D01*
G01X320872D02*
X321102Y89175D01*
X321294Y89434D01*
X321371Y89744D01*
X321294Y90054D01*
X321102Y90312D01*
X320757Y90467D01*
X320412Y90415D01*
X320067Y90209D01*
G01X325187Y78300D02*
Y84600D01*
X327067D01*
X327694Y84285D01*
X328164Y83550D01*
X328321Y82710D01*
X328164Y81870D01*
X327772Y81240D01*
X327067Y80925D01*
X325187D01*
G01X331487Y78300D02*
Y84600D01*
X333446D01*
X334072Y84285D01*
X334464Y83865D01*
X334621Y83025D01*
X334464Y82185D01*
X333994Y81660D01*
X333446Y81345D01*
X331487D01*
G01X333446D02*
X334621Y78300D01*
G01X340921D02*
X337787D01*
Y84600D01*
X340921D01*
G01X339667Y81555D02*
X337787D01*
G01X344009Y79140D02*
X344636Y78615D01*
X345341Y78300D01*
X345967D01*
X346594Y78615D01*
X347064Y79140D01*
X347299Y79875D01*
X347142Y80610D01*
X346751Y81240D01*
X346046Y81660D01*
X345106Y81870D01*
X344557Y82290D01*
X344322Y83025D01*
X344479Y83760D01*
X344871Y84285D01*
X345419Y84600D01*
X345967D01*
X346516Y84390D01*
X346986Y83865D01*
G01X350309Y79140D02*
X350936Y78615D01*
X351641Y78300D01*
X352267D01*
X352894Y78615D01*
X353364Y79140D01*
X353599Y79875D01*
X353442Y80610D01*
X353051Y81240D01*
X352346Y81660D01*
X351406Y81870D01*
X350857Y82290D01*
X350622Y83025D01*
X350779Y83760D01*
X351171Y84285D01*
X351719Y84600D01*
X352267D01*
X352816Y84390D01*
X353286Y83865D01*
G01X357236Y80400D02*
X359272D01*
G01X363066Y78300D02*
Y84600D01*
X366042D01*
G01X364946Y81555D02*
X363066D01*
G01X369914Y84600D02*
X371794D01*
G01X370854D02*
Y78300D01*
G01X369914D02*
X371794D01*
G01X377154Y84600D02*
Y78300D01*
G01X375352Y84600D02*
X378956D01*
G01X316516Y86022D02*
X386792D01*
G01X326934Y96594D02*
X326779Y96364D01*
X326676Y96096D01*
Y95789D01*
X326831Y95444D01*
X327089Y95176D01*
X327399Y94984D01*
X327916Y94831D01*
X328381Y94793D01*
X328846Y94869D01*
X329156Y94984D01*
X329466Y95214D01*
X329673Y95483D01*
X329776Y95751D01*
Y96019D01*
X329673Y96288D01*
X329518Y96518D01*
X329311Y96709D01*
G01X327193Y98123D02*
X326883Y98353D01*
X326728Y98621D01*
X326676Y98928D01*
X326779Y99311D01*
X327038Y99579D01*
X327348Y99656D01*
X327658Y99618D01*
X327916Y99464D01*
X328433Y98698D01*
X328794Y98353D01*
X329311Y98123D01*
X329776Y98046D01*
Y99656D01*
G01X324543Y104906D02*
Y108006D01*
X325502D01*
X325808Y107851D01*
X326000Y107644D01*
X326077Y107231D01*
X326000Y106818D01*
X325770Y106559D01*
X325502Y106404D01*
X324543D01*
G01X325502D02*
X326077Y104906D01*
G01X328870D02*
Y108006D01*
X327452Y105784D01*
X329368D01*
G01X331970Y104906D02*
Y108006D01*
X330552Y105784D01*
X332468D01*
G01X324343Y100706D02*
Y103806D01*
X325302D01*
X325608Y103651D01*
X325800Y103444D01*
X325877Y103031D01*
X325800Y102618D01*
X325570Y102359D01*
X325302Y102204D01*
X324343D01*
G01X325302D02*
X325877Y100706D01*
G01X328670D02*
Y103806D01*
X327252Y101584D01*
X329168D01*
G01X330467Y101171D02*
X330697Y100913D01*
X330965Y100758D01*
X331310Y100706D01*
X331655Y100809D01*
X331923Y101016D01*
X332115Y101378D01*
X332153Y101791D01*
X332077Y102204D01*
X331885Y102463D01*
X331617Y102669D01*
X331348Y102721D01*
X331080Y102669D01*
X330735Y102463D01*
X330850Y103806D01*
X331885D01*
G01X324343Y109010D02*
Y112110D01*
X325302D01*
X325608Y111955D01*
X325800Y111748D01*
X325877Y111335D01*
X325800Y110922D01*
X325570Y110663D01*
X325302Y110508D01*
X324343D01*
G01X325302D02*
X325877Y109010D01*
G01X328670D02*
Y112110D01*
X327252Y109888D01*
X329168D01*
G01X331233Y109010D02*
X331310Y109682D01*
X331425Y110250D01*
X331578Y110767D01*
X331770Y111335D01*
X332077Y112110D01*
X330543D01*
G01X320200Y130683D02*
X323300D01*
Y132217D01*
G01X320717Y133822D02*
X320407Y134052D01*
X320252Y134320D01*
X320200Y134627D01*
X320303Y135010D01*
X320562Y135278D01*
X320872Y135355D01*
X321182Y135317D01*
X321440Y135163D01*
X321957Y134397D01*
X322318Y134052D01*
X322835Y133822D01*
X323300Y133745D01*
Y135355D01*
G01X335300Y133200D02*
X328700D01*
G01X335300Y140200D02*
X328700D01*
G01X335300Y125200D02*
X328700D01*
G01X328600D02*
Y140200D01*
G01X335300Y132200D02*
X328700D01*
G01X324327Y130883D02*
X327427D01*
Y132417D01*
G01Y135210D02*
X324327D01*
X326549Y133792D01*
Y135708D01*
G01X332546Y75221D02*
X333504Y78321D01*
X334462Y75221D01*
G01X334117Y76306D02*
X332891D01*
G01X336604Y75221D02*
Y78321D01*
X336144Y77701D01*
G01Y75221D02*
X337064D01*
G01X334932Y96699D02*
X334777Y96469D01*
X334674Y96201D01*
Y95894D01*
X334829Y95549D01*
X335087Y95281D01*
X335397Y95089D01*
X335914Y94936D01*
X336379Y94898D01*
X336844Y94974D01*
X337154Y95089D01*
X337464Y95319D01*
X337671Y95588D01*
X337774Y95856D01*
Y96124D01*
X337671Y96393D01*
X337516Y96623D01*
X337309Y96814D01*
G01X337154Y98113D02*
X337516Y98343D01*
X337722Y98649D01*
X337774Y98994D01*
X337722Y99301D01*
X337464Y99608D01*
X337154Y99799D01*
X336844Y99838D01*
X336482Y99761D01*
X336224Y99493D01*
X336121Y99224D01*
Y98879D01*
G01Y99224D02*
X335966Y99454D01*
X335707Y99646D01*
X335397Y99723D01*
X335087Y99646D01*
X334829Y99454D01*
X334674Y99109D01*
X334726Y98764D01*
X334932Y98419D01*
G01X339632Y96499D02*
X339477Y96269D01*
X339374Y96001D01*
Y95694D01*
X339529Y95349D01*
X339787Y95081D01*
X340097Y94889D01*
X340614Y94736D01*
X341079Y94698D01*
X341544Y94774D01*
X341854Y94889D01*
X342164Y95119D01*
X342371Y95388D01*
X342474Y95656D01*
Y95924D01*
X342371Y96193D01*
X342216Y96423D01*
X342009Y96614D01*
G01X342474Y99216D02*
X339374D01*
X341596Y97798D01*
Y99714D01*
G01X348824Y98099D02*
Y87899D01*
X344224D01*
Y98099D01*
X348824D01*
G01Y92999D02*
X344224D01*
G01X331134Y96894D02*
X330979Y96664D01*
X330876Y96396D01*
Y96089D01*
X331031Y95744D01*
X331289Y95476D01*
X331599Y95284D01*
X332116Y95131D01*
X332581Y95093D01*
X333046Y95169D01*
X333356Y95284D01*
X333666Y95514D01*
X333873Y95783D01*
X333976Y96051D01*
Y96319D01*
X333873Y96588D01*
X333718Y96818D01*
X333511Y97009D01*
G01X333976Y99151D02*
X330876D01*
X331496Y98691D01*
G01X333976D02*
Y99611D01*
G01X354724Y98099D02*
Y87899D01*
X350124D01*
Y98099D01*
X354724D01*
G01Y92999D02*
X350124D01*
G01X335343Y100928D02*
Y104028D01*
X336302D01*
X336608Y103873D01*
X336800Y103666D01*
X336877Y103253D01*
X336800Y102840D01*
X336570Y102581D01*
X336302Y102426D01*
X335343D01*
G01X336302D02*
X336877Y100928D01*
G01X339210D02*
Y104028D01*
X338750Y103408D01*
G01Y100928D02*
X339670D01*
G01X341582Y102220D02*
X341850Y102581D01*
X342080Y102788D01*
X342387Y102891D01*
X342655Y102788D01*
X342847Y102581D01*
X343000Y102271D01*
X343038Y101910D01*
X343000Y101600D01*
X342847Y101290D01*
X342617Y101031D01*
X342348Y100928D01*
X342042Y101031D01*
X341773Y101341D01*
X341620Y101806D01*
X341582Y102323D01*
X341658Y102995D01*
X341773Y103356D01*
X341965Y103718D01*
X342233Y103976D01*
X342502Y104028D01*
X342770Y103925D01*
X342962Y103666D01*
G01X335343Y109224D02*
Y112324D01*
X336302D01*
X336608Y112169D01*
X336800Y111962D01*
X336877Y111549D01*
X336800Y111136D01*
X336570Y110877D01*
X336302Y110722D01*
X335343D01*
G01X336302D02*
X336877Y109224D01*
G01X339670D02*
Y112324D01*
X338252Y110102D01*
X340168D01*
G01X335243Y104828D02*
Y107928D01*
X336202D01*
X336508Y107773D01*
X336700Y107566D01*
X336777Y107153D01*
X336700Y106740D01*
X336470Y106481D01*
X336202Y106326D01*
X335243D01*
G01X336202D02*
X336777Y104828D01*
G01X339110D02*
Y107928D01*
X338650Y107308D01*
G01Y104828D02*
X339570D01*
G01X341482Y107411D02*
X341712Y107721D01*
X341980Y107876D01*
X342287Y107928D01*
X342670Y107825D01*
X342938Y107566D01*
X343015Y107256D01*
X342977Y106946D01*
X342823Y106688D01*
X342057Y106171D01*
X341712Y105810D01*
X341482Y105293D01*
X341405Y104828D01*
X343015D01*
G01X355140Y106961D02*
X348940D01*
Y110161D01*
X355140D01*
Y106961D01*
G01Y101361D02*
X348940D01*
Y104561D01*
X355140D01*
Y101361D01*
G01Y113057D02*
X348940D01*
Y116257D01*
X355140D01*
Y113057D01*
G01X330683Y113542D02*
Y116642D01*
X331642D01*
X331948Y116487D01*
X332140Y116280D01*
X332217Y115867D01*
X332140Y115454D01*
X331910Y115195D01*
X331642Y115040D01*
X330683D01*
G01X331642D02*
X332217Y113542D01*
G01X334473D02*
X334550Y114214D01*
X334665Y114782D01*
X334818Y115299D01*
X335010Y115867D01*
X335317Y116642D01*
X333783D01*
G01X337650Y113542D02*
X337918Y113594D01*
X338225Y113749D01*
X338417Y114007D01*
X338493Y114369D01*
X338417Y114730D01*
X338187Y115040D01*
X337842Y115195D01*
X337458D01*
X337228Y115299D01*
X337037Y115557D01*
X336960Y115919D01*
X337075Y116280D01*
X337343Y116539D01*
X337650Y116642D01*
X337957Y116539D01*
X338225Y116280D01*
X338340Y115919D01*
X338263Y115557D01*
X338072Y115299D01*
X337842Y115195D01*
X337458D01*
X337113Y115040D01*
X336883Y114730D01*
X336807Y114369D01*
X336883Y114007D01*
X337075Y113749D01*
X337382Y113594D01*
X337650Y113542D01*
G01X365700Y125042D02*
Y118242D01*
X350700D01*
Y125042D01*
X365700D01*
G01X330683Y117642D02*
Y120742D01*
X331642D01*
X331948Y120587D01*
X332140Y120380D01*
X332217Y119967D01*
X332140Y119554D01*
X331910Y119295D01*
X331642Y119140D01*
X330683D01*
G01X331642D02*
X332217Y117642D01*
G01X334473D02*
X334550Y118314D01*
X334665Y118882D01*
X334818Y119399D01*
X335010Y119967D01*
X335317Y120742D01*
X333783D01*
G01X336998Y118004D02*
X337267Y117745D01*
X337573Y117642D01*
X337880Y117745D01*
X338148Y118055D01*
X338340Y118520D01*
X338417Y118985D01*
Y119554D01*
X338340Y120019D01*
X338148Y120432D01*
X337918Y120639D01*
X337650Y120742D01*
X337343Y120639D01*
X337113Y120432D01*
X336960Y120122D01*
X336883Y119709D01*
X336960Y119347D01*
X337152Y118985D01*
X337382Y118779D01*
X337650Y118727D01*
X337957Y118830D01*
X338187Y119089D01*
X338417Y119554D01*
G01X365970Y144984D02*
X349431D01*
Y153252D01*
X365970D01*
Y144984D01*
G01X346472Y141596D02*
X346702Y141906D01*
X346970Y142061D01*
X347277Y142113D01*
X347660Y142010D01*
X347928Y141751D01*
X348005Y141441D01*
X347967Y141131D01*
X347813Y140873D01*
X347047Y140356D01*
X346702Y139995D01*
X346472Y139478D01*
X346395Y139013D01*
X348005D01*
G01X366070Y135148D02*
X349531D01*
Y143416D01*
X366070D01*
Y135148D01*
G01X335400Y140200D02*
Y125200D01*
G01X343773Y133300D02*
X337173D01*
G01X343773Y140300D02*
X337173D01*
G01X343773Y125300D02*
X337173D01*
G01X337073D02*
Y140300D01*
G01X343773Y132300D02*
X337173D01*
G01X343873Y140300D02*
Y125300D01*
G01X365700Y133542D02*
Y126742D01*
X350700D01*
Y133542D01*
X365700D01*
G01X347072Y152632D02*
X347302Y152942D01*
X347570Y153097D01*
X347877Y153149D01*
X348260Y153046D01*
X348528Y152787D01*
X348605Y152477D01*
X348567Y152167D01*
X348413Y151909D01*
X347647Y151392D01*
X347302Y151031D01*
X347072Y150514D01*
X346995Y150049D01*
X348605D01*
G01X352623Y158449D02*
Y161549D01*
X354079D01*
G01X353543Y160051D02*
X352623D01*
G01X355646Y158862D02*
X355953Y158604D01*
X356298Y158449D01*
X356604D01*
X356911Y158604D01*
X357141Y158862D01*
X357256Y159224D01*
X357179Y159586D01*
X356988Y159896D01*
X356643Y160102D01*
X356183Y160206D01*
X355914Y160412D01*
X355799Y160774D01*
X355876Y161136D01*
X356068Y161394D01*
X356336Y161549D01*
X356604D01*
X356873Y161446D01*
X357103Y161187D01*
G01X358823Y161032D02*
X359053Y161342D01*
X359321Y161497D01*
X359628Y161549D01*
X360011Y161446D01*
X360279Y161187D01*
X360356Y160877D01*
X360318Y160567D01*
X360164Y160309D01*
X359398Y159792D01*
X359053Y159431D01*
X358823Y158914D01*
X358746Y158449D01*
X360356D01*
G01X352623Y154613D02*
Y157713D01*
X354079D01*
G01X353543Y156215D02*
X352623D01*
G01X355646Y155026D02*
X355953Y154768D01*
X356298Y154613D01*
X356604D01*
X356911Y154768D01*
X357141Y155026D01*
X357256Y155388D01*
X357179Y155750D01*
X356988Y156060D01*
X356643Y156266D01*
X356183Y156370D01*
X355914Y156576D01*
X355799Y156938D01*
X355876Y157300D01*
X356068Y157558D01*
X356336Y157713D01*
X356604D01*
X356873Y157610D01*
X357103Y157351D01*
G01X360011Y154613D02*
Y157713D01*
X358593Y155491D01*
X360509D01*
G01X422300Y17698D02*
X367894D01*
G01D02*
Y235414D01*
X455492D01*
Y17698D01*
X451300D01*
G01X356759Y92294D02*
X359759D01*
G01X359859Y95394D02*
Y89194D01*
X356659D01*
Y95394D01*
X359859D01*
G01X361259Y92294D02*
X364259D01*
G01X364359Y95394D02*
Y89194D01*
X361159D01*
Y95394D01*
X364359D01*
G01X376794Y104505D02*
X370494D01*
Y106385D01*
X370809Y107012D01*
X371544Y107482D01*
X372384Y107639D01*
X373224Y107482D01*
X373854Y107090D01*
X374169Y106385D01*
Y104505D01*
G01X376794Y110805D02*
X370494D01*
Y112764D01*
X370809Y113390D01*
X371229Y113782D01*
X372069Y113939D01*
X372909Y113782D01*
X373434Y113312D01*
X373749Y112764D01*
Y110805D01*
G01Y112764D02*
X376794Y113939D01*
G01Y120239D02*
Y117105D01*
X370494D01*
Y120239D01*
G01X373539Y118985D02*
Y117105D01*
G01X375954Y123327D02*
X376479Y123954D01*
X376794Y124659D01*
Y125285D01*
X376479Y125912D01*
X375954Y126382D01*
X375219Y126617D01*
X374484Y126460D01*
X373854Y126069D01*
X373434Y125364D01*
X373224Y124424D01*
X372804Y123875D01*
X372069Y123640D01*
X371334Y123797D01*
X370809Y124189D01*
X370494Y124737D01*
Y125285D01*
X370704Y125834D01*
X371229Y126304D01*
G01X375954Y129627D02*
X376479Y130254D01*
X376794Y130959D01*
Y131585D01*
X376479Y132212D01*
X375954Y132682D01*
X375219Y132917D01*
X374484Y132760D01*
X373854Y132369D01*
X373434Y131664D01*
X373224Y130724D01*
X372804Y130175D01*
X372069Y129940D01*
X371334Y130097D01*
X370809Y130489D01*
X370494Y131037D01*
Y131585D01*
X370704Y132134D01*
X371229Y132604D01*
G01X374694Y136554D02*
Y138590D01*
G01X376794Y142384D02*
X370494D01*
Y145360D01*
G01X373539Y144264D02*
Y142384D01*
G01X370494Y149232D02*
Y151112D01*
G01Y150172D02*
X376794D01*
G01Y149232D02*
Y151112D01*
G01X370494Y156472D02*
X376794D01*
G01X370494Y154670D02*
Y158274D01*
G01X359760Y104561D02*
X365960D01*
Y101361D01*
X359760D01*
Y104561D01*
G01Y116257D02*
X365960D01*
Y113057D01*
X359760D01*
Y116257D01*
G01Y110161D02*
X365960D01*
Y106961D01*
X359760D01*
Y110161D01*
G01X367200Y132313D02*
Y135413D01*
X366740Y134793D01*
G01Y132313D02*
X367660D01*
G01X366700Y154149D02*
Y157249D01*
X366240Y156629D01*
G01Y154149D02*
X367160D01*
G01X364936Y181927D02*
X365246Y182119D01*
X365453Y182349D01*
X365556Y182617D01*
X365453Y182924D01*
X365246Y183154D01*
X364936Y183384D01*
X364523Y183461D01*
X362456D01*
G01X365556Y185794D02*
X362456D01*
X363076Y185334D01*
G01X365556D02*
Y186254D01*
G01X365091Y188051D02*
X365349Y188281D01*
X365504Y188549D01*
X365556Y188894D01*
X365453Y189239D01*
X365246Y189507D01*
X364884Y189699D01*
X364471Y189737D01*
X364058Y189661D01*
X363799Y189469D01*
X363593Y189201D01*
X363541Y188932D01*
X363593Y188664D01*
X363799Y188319D01*
X362456Y188434D01*
Y189469D01*
G01X386792Y86022D02*
Y-52954D01*
G01X382791Y4193D02*
X382636Y3963D01*
X382533Y3695D01*
Y3388D01*
X382688Y3043D01*
X382946Y2775D01*
X383256Y2583D01*
X383773Y2430D01*
X384238Y2392D01*
X384703Y2468D01*
X385013Y2583D01*
X385323Y2813D01*
X385530Y3082D01*
X385633Y3350D01*
Y3618D01*
X385530Y3887D01*
X385375Y4117D01*
X385168Y4308D01*
G01X383050Y5722D02*
X382740Y5952D01*
X382585Y6220D01*
X382533Y6527D01*
X382636Y6910D01*
X382895Y7178D01*
X383205Y7255D01*
X383515Y7217D01*
X383773Y7063D01*
X384290Y6297D01*
X384651Y5952D01*
X385168Y5722D01*
X385633Y5645D01*
Y7255D01*
G01Y10010D02*
X382533D01*
X384755Y8592D01*
Y10508D01*
G01X387991Y4193D02*
X387836Y3963D01*
X387733Y3695D01*
Y3388D01*
X387888Y3043D01*
X388146Y2775D01*
X388456Y2583D01*
X388973Y2430D01*
X389438Y2392D01*
X389903Y2468D01*
X390213Y2583D01*
X390523Y2813D01*
X390730Y3082D01*
X390833Y3350D01*
Y3618D01*
X390730Y3887D01*
X390575Y4117D01*
X390368Y4308D01*
G01X388250Y5722D02*
X387940Y5952D01*
X387785Y6220D01*
X387733Y6527D01*
X387836Y6910D01*
X388095Y7178D01*
X388405Y7255D01*
X388715Y7217D01*
X388973Y7063D01*
X389490Y6297D01*
X389851Y5952D01*
X390368Y5722D01*
X390833Y5645D01*
Y7255D01*
G01X390213Y8707D02*
X390575Y8937D01*
X390781Y9243D01*
X390833Y9588D01*
X390781Y9895D01*
X390523Y10202D01*
X390213Y10393D01*
X389903Y10432D01*
X389541Y10355D01*
X389283Y10087D01*
X389180Y9818D01*
Y9473D01*
G01Y9818D02*
X389025Y10048D01*
X388766Y10240D01*
X388456Y10317D01*
X388146Y10240D01*
X387888Y10048D01*
X387733Y9703D01*
X387785Y9358D01*
X387991Y9013D01*
G01X392291Y4193D02*
X392136Y3963D01*
X392033Y3695D01*
Y3388D01*
X392188Y3043D01*
X392446Y2775D01*
X392756Y2583D01*
X393273Y2430D01*
X393738Y2392D01*
X394203Y2468D01*
X394513Y2583D01*
X394823Y2813D01*
X395030Y3082D01*
X395133Y3350D01*
Y3618D01*
X395030Y3887D01*
X394875Y4117D01*
X394668Y4308D01*
G01X395133Y6450D02*
X392033D01*
X392653Y5990D01*
G01X395133D02*
Y6910D01*
G01X394771Y8898D02*
X395030Y9167D01*
X395133Y9473D01*
X395030Y9780D01*
X394720Y10048D01*
X394255Y10240D01*
X393790Y10317D01*
X393221D01*
X392756Y10240D01*
X392343Y10048D01*
X392136Y9818D01*
X392033Y9550D01*
X392136Y9243D01*
X392343Y9013D01*
X392653Y8860D01*
X393066Y8783D01*
X393428Y8860D01*
X393790Y9052D01*
X393996Y9282D01*
X394048Y9550D01*
X393945Y9857D01*
X393686Y10087D01*
X393221Y10317D01*
G01X396291Y4193D02*
X396136Y3963D01*
X396033Y3695D01*
Y3388D01*
X396188Y3043D01*
X396446Y2775D01*
X396756Y2583D01*
X397273Y2430D01*
X397738Y2392D01*
X398203Y2468D01*
X398513Y2583D01*
X398823Y2813D01*
X399030Y3082D01*
X399133Y3350D01*
Y3618D01*
X399030Y3887D01*
X398875Y4117D01*
X398668Y4308D01*
G01X396550Y5722D02*
X396240Y5952D01*
X396085Y6220D01*
X396033Y6527D01*
X396136Y6910D01*
X396395Y7178D01*
X396705Y7255D01*
X397015Y7217D01*
X397273Y7063D01*
X397790Y6297D01*
X398151Y5952D01*
X398668Y5722D01*
X399133Y5645D01*
Y7255D01*
G01X396033Y9550D02*
X396136Y9243D01*
X396395Y9013D01*
X396705Y8860D01*
X397118Y8745D01*
X397583Y8707D01*
X398048Y8745D01*
X398461Y8860D01*
X398771Y9013D01*
X399030Y9243D01*
X399133Y9550D01*
X399030Y9857D01*
X398771Y10087D01*
X398461Y10240D01*
X398048Y10355D01*
X397583Y10393D01*
X397118Y10355D01*
X396705Y10240D01*
X396395Y10087D01*
X396136Y9857D01*
X396033Y9550D01*
G01X378547Y21593D02*
X378317Y21748D01*
X378049Y21851D01*
X377742D01*
X377397Y21696D01*
X377129Y21438D01*
X376937Y21128D01*
X376784Y20611D01*
X376746Y20146D01*
X376822Y19681D01*
X376937Y19371D01*
X377167Y19061D01*
X377436Y18854D01*
X377704Y18751D01*
X377972D01*
X378241Y18854D01*
X378471Y19009D01*
X378662Y19216D01*
G01X380076Y21334D02*
X380306Y21644D01*
X380574Y21799D01*
X380881Y21851D01*
X381264Y21748D01*
X381532Y21489D01*
X381609Y21179D01*
X381571Y20869D01*
X381417Y20611D01*
X380651Y20094D01*
X380306Y19733D01*
X380076Y19216D01*
X379999Y18751D01*
X381609D01*
G01X377947Y13118D02*
X377717Y13273D01*
X377449Y13376D01*
X377142D01*
X376797Y13221D01*
X376529Y12963D01*
X376337Y12653D01*
X376184Y12136D01*
X376146Y11671D01*
X376222Y11206D01*
X376337Y10896D01*
X376567Y10586D01*
X376836Y10379D01*
X377104Y10276D01*
X377372D01*
X377641Y10379D01*
X377871Y10534D01*
X378062Y10741D01*
G01X379361Y10896D02*
X379591Y10534D01*
X379897Y10328D01*
X380242Y10276D01*
X380549Y10328D01*
X380856Y10586D01*
X381047Y10896D01*
X381086Y11206D01*
X381009Y11568D01*
X380741Y11826D01*
X380472Y11929D01*
X380127D01*
G01X380472D02*
X380702Y12084D01*
X380894Y12343D01*
X380971Y12653D01*
X380894Y12963D01*
X380702Y13221D01*
X380357Y13376D01*
X380012Y13324D01*
X379667Y13118D01*
G01X378047Y28567D02*
X377817Y28722D01*
X377549Y28825D01*
X377242D01*
X376897Y28670D01*
X376629Y28412D01*
X376437Y28102D01*
X376284Y27585D01*
X376246Y27120D01*
X376322Y26655D01*
X376437Y26345D01*
X376667Y26035D01*
X376936Y25828D01*
X377204Y25725D01*
X377472D01*
X377741Y25828D01*
X377971Y25983D01*
X378162Y26190D01*
G01X380304Y25725D02*
Y28825D01*
X379844Y28205D01*
G01Y25725D02*
X380764D01*
G01X395744Y33446D02*
X396752D01*
Y29509D01*
X394344D01*
G01X391244D02*
X379705D01*
Y223603D01*
X443681D01*
G01X377200Y50811D02*
X377045Y50964D01*
X376786Y51079D01*
X376425Y51156D01*
X376115Y51079D01*
X375908Y50926D01*
X375753Y50657D01*
Y49622D01*
X378853D01*
Y50887D01*
X378646Y51156D01*
X378336Y51309D01*
X377975Y51386D01*
X377613Y51309D01*
X377303Y51079D01*
X377200Y50811D01*
Y49622D01*
G01X376270Y52876D02*
X375960Y53106D01*
X375805Y53374D01*
X375753Y53681D01*
X375856Y54064D01*
X376115Y54332D01*
X376425Y54409D01*
X376735Y54371D01*
X376993Y54217D01*
X377510Y53451D01*
X377871Y53106D01*
X378388Y52876D01*
X378853Y52799D01*
Y54409D01*
G01X377374Y42111D02*
X377219Y42264D01*
X376960Y42379D01*
X376599Y42456D01*
X376289Y42379D01*
X376082Y42226D01*
X375927Y41957D01*
Y40922D01*
X379027D01*
Y42187D01*
X378820Y42456D01*
X378510Y42609D01*
X378149Y42686D01*
X377787Y42609D01*
X377477Y42379D01*
X377374Y42111D01*
Y40922D01*
G01X378407Y44061D02*
X378769Y44291D01*
X378975Y44597D01*
X379027Y44942D01*
X378975Y45249D01*
X378717Y45556D01*
X378407Y45747D01*
X378097Y45786D01*
X377735Y45709D01*
X377477Y45441D01*
X377374Y45172D01*
Y44827D01*
G01Y45172D02*
X377219Y45402D01*
X376960Y45594D01*
X376650Y45671D01*
X376340Y45594D01*
X376082Y45402D01*
X375927Y45057D01*
X375979Y44712D01*
X376185Y44367D01*
G01X400503Y32502D02*
X397403D01*
X398023Y32042D01*
G01X400503D02*
Y32962D01*
G01Y35602D02*
X397403D01*
X398023Y35142D01*
G01X400503D02*
Y36062D01*
G01X396793Y42086D02*
X390039D01*
G01D02*
Y53153D01*
G01X433544Y33446D02*
X435807D01*
Y90532D01*
X387579D01*
Y33446D01*
X389844D01*
G01X377226Y60611D02*
X377071Y60764D01*
X376812Y60879D01*
X376451Y60956D01*
X376141Y60879D01*
X375934Y60726D01*
X375779Y60457D01*
Y59422D01*
X378879D01*
Y60687D01*
X378672Y60956D01*
X378362Y61109D01*
X378001Y61186D01*
X377639Y61109D01*
X377329Y60879D01*
X377226Y60611D01*
Y59422D01*
G01X378879Y63404D02*
X375779D01*
X376399Y62944D01*
G01X378879D02*
Y63864D01*
G01X390039Y60153D02*
Y71220D01*
G01D02*
X395193D01*
G01X390102Y78397D02*
Y81497D01*
X389642Y80877D01*
G01Y78397D02*
X390562D01*
G01X393202Y81497D02*
X392895Y81394D01*
X392665Y81135D01*
X392512Y80825D01*
X392397Y80412D01*
X392359Y79947D01*
X392397Y79482D01*
X392512Y79069D01*
X392665Y78759D01*
X392895Y78500D01*
X393202Y78397D01*
X393509Y78500D01*
X393739Y78759D01*
X393892Y79069D01*
X394007Y79482D01*
X394045Y79947D01*
X394007Y80412D01*
X393892Y80825D01*
X393739Y81135D01*
X393509Y81394D01*
X393202Y81497D01*
G01X424273Y9075D02*
X423803Y9390D01*
X423255Y9600D01*
X422628D01*
X421923Y9285D01*
X421375Y8760D01*
X420983Y8130D01*
X420670Y7080D01*
X420592Y6135D01*
X420748Y5190D01*
X420983Y4560D01*
X421453Y3930D01*
X422002Y3510D01*
X422550Y3300D01*
X423098D01*
X423647Y3510D01*
X424117Y3825D01*
X424508Y4245D01*
G01X428850Y3300D02*
X428223Y3405D01*
X427675Y3825D01*
X427205Y4455D01*
X426892Y5190D01*
X426735Y6030D01*
Y6870D01*
X426892Y7710D01*
X427205Y8445D01*
X427675Y9075D01*
X428223Y9495D01*
X428850Y9600D01*
X429477Y9495D01*
X430025Y9075D01*
X430495Y8445D01*
X430808Y7710D01*
X430965Y6870D01*
Y6030D01*
X430808Y5190D01*
X430495Y4455D01*
X430025Y3825D01*
X429477Y3405D01*
X428850Y3300D01*
G01X433348D02*
Y9600D01*
X436952Y3300D01*
Y9600D01*
G01X439648Y3300D02*
Y9600D01*
X443252Y3300D01*
Y9600D01*
G01X447750Y3300D02*
Y9600D01*
X446810Y8340D01*
G01Y3300D02*
X448690D01*
G01X402000Y8400D02*
Y14600D01*
X405200D01*
Y8400D01*
X402000D01*
G01X405100Y11500D02*
X402100D01*
G01X406600Y8400D02*
Y14600D01*
X409800D01*
Y8400D01*
X406600D01*
G01X409700Y11500D02*
X406700D01*
G01X411200Y8500D02*
Y14700D01*
X414400D01*
Y8500D01*
X411200D01*
G01X414300Y11600D02*
X411300D01*
G01X415600Y8500D02*
Y14700D01*
X418800D01*
Y8500D01*
X415600D01*
G01X418700Y11600D02*
X415700D01*
G01X423005Y14540D02*
X423632Y14015D01*
X424337Y13700D01*
X424963D01*
X425590Y14015D01*
X426060Y14540D01*
X426295Y15275D01*
X426138Y16010D01*
X425747Y16640D01*
X425042Y17060D01*
X424102Y17270D01*
X423553Y17690D01*
X423318Y18425D01*
X423475Y19160D01*
X423867Y19685D01*
X424415Y20000D01*
X424963D01*
X425512Y19790D01*
X425982Y19265D01*
G01X429462Y13700D02*
Y20000D01*
X432438D01*
G01X431342Y16955D02*
X429462D01*
G01X435683Y13700D02*
Y20000D01*
X437563D01*
X438190Y19685D01*
X438660Y18950D01*
X438817Y18110D01*
X438660Y17270D01*
X438268Y16640D01*
X437563Y16325D01*
X435683D01*
G01X442688Y15800D02*
X444568D01*
G01X443550Y17165D02*
Y14435D01*
G01X432214Y26414D02*
Y24192D01*
X432367Y23727D01*
X432674Y23417D01*
X433057Y23314D01*
X433440Y23417D01*
X433747Y23727D01*
X433900Y24192D01*
Y26414D01*
G01X435429Y24606D02*
X435697Y24967D01*
X435927Y25174D01*
X436234Y25277D01*
X436502Y25174D01*
X436694Y24967D01*
X436847Y24657D01*
X436885Y24296D01*
X436847Y23986D01*
X436694Y23676D01*
X436464Y23417D01*
X436195Y23314D01*
X435889Y23417D01*
X435620Y23727D01*
X435467Y24192D01*
X435429Y24709D01*
X435505Y25381D01*
X435620Y25742D01*
X435812Y26104D01*
X436080Y26362D01*
X436349Y26414D01*
X436617Y26311D01*
X436809Y26052D01*
G01X426220Y23674D02*
X425910Y23904D01*
X425755Y24172D01*
X425703Y24479D01*
X425806Y24862D01*
X426065Y25130D01*
X426375Y25207D01*
X426685Y25169D01*
X426943Y25015D01*
X427460Y24249D01*
X427821Y23904D01*
X428338Y23674D01*
X428803Y23597D01*
Y25207D01*
G01X425703Y27502D02*
X425806Y27195D01*
X426065Y26965D01*
X426375Y26812D01*
X426788Y26697D01*
X427253Y26659D01*
X427718Y26697D01*
X428131Y26812D01*
X428441Y26965D01*
X428700Y27195D01*
X428803Y27502D01*
X428700Y27809D01*
X428441Y28039D01*
X428131Y28192D01*
X427718Y28307D01*
X427253Y28345D01*
X426788Y28307D01*
X426375Y28192D01*
X426065Y28039D01*
X425806Y27809D01*
X425703Y27502D01*
G01X443681Y223603D02*
Y29509D01*
X432044D01*
G01X429044D02*
X426634D01*
Y33446D01*
X427644D01*
G01X433347Y42086D02*
X428193D01*
G01X433347D02*
Y54153D01*
G01X426593Y71220D02*
X433347D01*
G01Y59153D02*
Y71220D01*
G01X429176Y78297D02*
Y81397D01*
X428716Y80777D01*
G01Y78297D02*
X429636D01*
G01X445846Y120742D02*
X445691Y120895D01*
X445432Y121010D01*
X445071Y121087D01*
X444761Y121010D01*
X444554Y120857D01*
X444399Y120588D01*
Y119553D01*
X447499D01*
Y120818D01*
X447292Y121087D01*
X446982Y121240D01*
X446621Y121317D01*
X446259Y121240D01*
X445949Y121010D01*
X445846Y120742D01*
Y119553D01*
G01X444916Y122807D02*
X444606Y123037D01*
X444451Y123305D01*
X444399Y123612D01*
X444502Y123995D01*
X444761Y124263D01*
X445071Y124340D01*
X445381Y124302D01*
X445639Y124148D01*
X446156Y123382D01*
X446517Y123037D01*
X447034Y122807D01*
X447499Y122730D01*
Y124340D01*
G01X447484Y141277D02*
X444384Y142235D01*
X447484Y143193D01*
G01X446399Y142848D02*
Y141622D01*
G01X447484Y145335D02*
X447432Y145603D01*
X447277Y145910D01*
X447019Y146102D01*
X446657Y146178D01*
X446296Y146102D01*
X445986Y145872D01*
X445831Y145527D01*
Y145143D01*
X445727Y144913D01*
X445469Y144722D01*
X445107Y144645D01*
X444746Y144760D01*
X444487Y145028D01*
X444384Y145335D01*
X444487Y145642D01*
X444746Y145910D01*
X445107Y146025D01*
X445469Y145948D01*
X445727Y145757D01*
X445831Y145527D01*
Y145143D01*
X445986Y144798D01*
X446296Y144568D01*
X446657Y144492D01*
X447019Y144568D01*
X447277Y144760D01*
X447432Y145067D01*
X447484Y145335D01*
G01X447384Y152177D02*
X444284Y153135D01*
X447384Y154093D01*
G01X446299Y153748D02*
Y152522D01*
G01X447384Y156158D02*
X446712Y156235D01*
X446144Y156350D01*
X445627Y156503D01*
X445059Y156695D01*
X444284Y157002D01*
Y155468D01*
G01X455917Y-335560D02*
X456544Y-336085D01*
X457249Y-336400D01*
X457875D01*
X458502Y-336085D01*
X458972Y-335560D01*
X459207Y-334825D01*
X459050Y-334090D01*
X458659Y-333460D01*
X457954Y-333040D01*
X457014Y-332830D01*
X456465Y-332410D01*
X456230Y-331675D01*
X456387Y-330940D01*
X456779Y-330415D01*
X457327Y-330100D01*
X457875D01*
X458424Y-330310D01*
X458894Y-330835D01*
G01X462217Y-336400D02*
Y-330100D01*
G01X465507D02*
Y-336400D01*
G01Y-333250D02*
X462217D01*
G01X469222Y-330100D02*
X471102D01*
G01X470162D02*
Y-336400D01*
G01X469222D02*
X471102D01*
G01X478029D02*
X474895D01*
Y-330100D01*
X478029D01*
G01X476775Y-333145D02*
X474895D01*
G01X480960Y-336400D02*
Y-330100D01*
X484564Y-336400D01*
Y-330100D01*
G01X488905Y-337555D02*
X489219Y-336190D01*
G01X495362Y-330100D02*
Y-336400D01*
G01X493560Y-330100D02*
X497164D01*
G01X499704Y-336400D02*
X501662Y-330100D01*
X503620Y-336400D01*
G01X502915Y-334195D02*
X500409D01*
G01X507022Y-330100D02*
X508902D01*
G01X507962D02*
Y-336400D01*
G01X507022D02*
X508902D01*
G01X511912Y-330100D02*
X513009Y-336400D01*
X514262Y-330100D01*
X515515Y-336400D01*
X516612Y-330100D01*
G01X518604Y-336400D02*
X520562Y-330100D01*
X522520Y-336400D01*
G01X521815Y-334195D02*
X519309D01*
G01X525060Y-336400D02*
Y-330100D01*
X528664Y-336400D01*
Y-330100D01*
G01X537895Y-336400D02*
Y-330100D01*
X539854D01*
X540480Y-330415D01*
X540872Y-330835D01*
X541029Y-331675D01*
X540872Y-332515D01*
X540402Y-333040D01*
X539854Y-333355D01*
X537895D01*
G01X539854D02*
X541029Y-336400D01*
G01X545762Y-336610D02*
X545605Y-336505D01*
Y-336295D01*
X545762Y-336190D01*
X545919Y-336295D01*
Y-336505D01*
X545762Y-336610D01*
G01X552062Y-336400D02*
X551435Y-336295D01*
X550887Y-335875D01*
X550417Y-335245D01*
X550104Y-334510D01*
X549947Y-333670D01*
Y-332830D01*
X550104Y-331990D01*
X550417Y-331255D01*
X550887Y-330625D01*
X551435Y-330205D01*
X552062Y-330100D01*
X552689Y-330205D01*
X553237Y-330625D01*
X553707Y-331255D01*
X554020Y-331990D01*
X554177Y-332830D01*
Y-333670D01*
X554020Y-334510D01*
X553707Y-335245D01*
X553237Y-335875D01*
X552689Y-336295D01*
X552062Y-336400D01*
G01X558362Y-336610D02*
X558205Y-336505D01*
Y-336295D01*
X558362Y-336190D01*
X558519Y-336295D01*
Y-336505D01*
X558362Y-336610D01*
G01X566385Y-330625D02*
X565915Y-330310D01*
X565367Y-330100D01*
X564740D01*
X564035Y-330415D01*
X563487Y-330940D01*
X563095Y-331570D01*
X562782Y-332620D01*
X562704Y-333565D01*
X562860Y-334510D01*
X563095Y-335140D01*
X563565Y-335770D01*
X564114Y-336190D01*
X564662Y-336400D01*
X565210D01*
X565759Y-336190D01*
X566229Y-335875D01*
X566620Y-335455D01*
G01X570962Y-336610D02*
X570805Y-336505D01*
Y-336295D01*
X570962Y-336190D01*
X571119Y-336295D01*
Y-336505D01*
X570962Y-336610D01*
G01X455839Y-326400D02*
Y-320100D01*
G01X458815D02*
X455839Y-323985D01*
G01X459285Y-326400D02*
X457170Y-322200D01*
G01X462139Y-320100D02*
Y-324615D01*
X462452Y-325560D01*
X463079Y-326190D01*
X463862Y-326400D01*
X464645Y-326190D01*
X465272Y-325560D01*
X465585Y-324615D01*
Y-320100D01*
G01X471729Y-326400D02*
X468595D01*
Y-320100D01*
X471729D01*
G01X470475Y-323145D02*
X468595D01*
G01X475522Y-320100D02*
X477402D01*
G01X476462D02*
Y-326400D01*
G01X475522D02*
X477402D01*
G01X487417Y-325560D02*
X488044Y-326085D01*
X488749Y-326400D01*
X489375D01*
X490002Y-326085D01*
X490472Y-325560D01*
X490707Y-324825D01*
X490550Y-324090D01*
X490159Y-323460D01*
X489454Y-323040D01*
X488514Y-322830D01*
X487965Y-322410D01*
X487730Y-321675D01*
X487887Y-320940D01*
X488279Y-320415D01*
X488827Y-320100D01*
X489375D01*
X489924Y-320310D01*
X490394Y-320835D01*
G01X493717Y-326400D02*
Y-320100D01*
G01X497007D02*
Y-326400D01*
G01Y-323250D02*
X493717D01*
G01X499704Y-326400D02*
X501662Y-320100D01*
X503620Y-326400D01*
G01X502915Y-324195D02*
X500409D01*
G01X506160Y-326400D02*
Y-320100D01*
X509764Y-326400D01*
Y-320100D01*
G01X518917Y-326400D02*
Y-320100D01*
G01X522207D02*
Y-326400D01*
G01Y-323250D02*
X518917D01*
G01X525217Y-325560D02*
X525844Y-326085D01*
X526549Y-326400D01*
X527175D01*
X527802Y-326085D01*
X528272Y-325560D01*
X528507Y-324825D01*
X528350Y-324090D01*
X527959Y-323460D01*
X527254Y-323040D01*
X526314Y-322830D01*
X525765Y-322410D01*
X525530Y-321675D01*
X525687Y-320940D01*
X526079Y-320415D01*
X526627Y-320100D01*
X527175D01*
X527724Y-320310D01*
X528194Y-320835D01*
G01X532222Y-320100D02*
X534102D01*
G01X533162D02*
Y-326400D01*
G01X532222D02*
X534102D01*
G01X537504D02*
X539462Y-320100D01*
X541420Y-326400D01*
G01X540715Y-324195D02*
X538209D01*
G01X543960Y-326400D02*
Y-320100D01*
X547564Y-326400D01*
Y-320100D01*
G01X552532Y-323250D02*
X554099D01*
Y-325140D01*
X553629Y-325770D01*
X553080Y-326190D01*
X552297Y-326400D01*
X551514Y-326190D01*
X550965Y-325770D01*
X550495Y-325140D01*
X550182Y-324405D01*
X550025Y-323565D01*
Y-322830D01*
X550182Y-322200D01*
X550495Y-321465D01*
X550965Y-320835D01*
X551435Y-320415D01*
X552062Y-320100D01*
X552610D01*
X553237Y-320310D01*
X553707Y-320730D01*
G01X558205Y-327555D02*
X558519Y-326190D01*
G01X564662Y-320100D02*
Y-326400D01*
G01X562860Y-320100D02*
X566464D01*
G01X569004Y-326400D02*
X570962Y-320100D01*
X572920Y-326400D01*
G01X572215Y-324195D02*
X569709D01*
G01X577262Y-326400D02*
X576635Y-326295D01*
X576087Y-325875D01*
X575617Y-325245D01*
X575304Y-324510D01*
X575147Y-323670D01*
Y-322830D01*
X575304Y-321990D01*
X575617Y-321255D01*
X576087Y-320625D01*
X576635Y-320205D01*
X577262Y-320100D01*
X577889Y-320205D01*
X578437Y-320625D01*
X578907Y-321255D01*
X579220Y-321990D01*
X579377Y-322830D01*
Y-323670D01*
X579220Y-324510D01*
X578907Y-325245D01*
X578437Y-325875D01*
X577889Y-326295D01*
X577262Y-326400D01*
G01X589862D02*
Y-323565D01*
X588295Y-320100D01*
G01X591429D02*
X589862Y-323565D01*
G01X594439Y-320100D02*
Y-324615D01*
X594752Y-325560D01*
X595379Y-326190D01*
X596162Y-326400D01*
X596945Y-326190D01*
X597572Y-325560D01*
X597885Y-324615D01*
Y-320100D01*
G01X600504Y-326400D02*
X602462Y-320100D01*
X604420Y-326400D01*
G01X603715Y-324195D02*
X601209D01*
G01X606960Y-326400D02*
Y-320100D01*
X610564Y-326400D01*
Y-320100D01*
G01X455760Y-316400D02*
Y-310100D01*
X459364Y-316400D01*
Y-310100D01*
G01X463862Y-316400D02*
X463235Y-316295D01*
X462687Y-315875D01*
X462217Y-315245D01*
X461904Y-314510D01*
X461747Y-313670D01*
Y-312830D01*
X461904Y-311990D01*
X462217Y-311255D01*
X462687Y-310625D01*
X463235Y-310205D01*
X463862Y-310100D01*
X464489Y-310205D01*
X465037Y-310625D01*
X465507Y-311255D01*
X465820Y-311990D01*
X465977Y-312830D01*
Y-313670D01*
X465820Y-314510D01*
X465507Y-315245D01*
X465037Y-315875D01*
X464489Y-316295D01*
X463862Y-316400D01*
G01X470162Y-316610D02*
X470005Y-316505D01*
Y-316295D01*
X470162Y-316190D01*
X470319Y-316295D01*
Y-316505D01*
X470162Y-316610D01*
G01X476462Y-316400D02*
Y-310100D01*
X475522Y-311360D01*
G01Y-316400D02*
X477402D01*
G01X482762D02*
X483310Y-316295D01*
X483937Y-315980D01*
X484329Y-315455D01*
X484485Y-314720D01*
X484329Y-313985D01*
X483859Y-313355D01*
X483154Y-313040D01*
X482370D01*
X481900Y-312830D01*
X481509Y-312305D01*
X481352Y-311570D01*
X481587Y-310835D01*
X482135Y-310310D01*
X482762Y-310100D01*
X483389Y-310310D01*
X483937Y-310835D01*
X484172Y-311570D01*
X484015Y-312305D01*
X483624Y-312830D01*
X483154Y-313040D01*
X482370D01*
X481665Y-313355D01*
X481195Y-313985D01*
X481039Y-314720D01*
X481195Y-315455D01*
X481587Y-315980D01*
X482214Y-316295D01*
X482762Y-316400D01*
G01X489062D02*
X489610Y-316295D01*
X490237Y-315980D01*
X490629Y-315455D01*
X490785Y-314720D01*
X490629Y-313985D01*
X490159Y-313355D01*
X489454Y-313040D01*
X488670D01*
X488200Y-312830D01*
X487809Y-312305D01*
X487652Y-311570D01*
X487887Y-310835D01*
X488435Y-310310D01*
X489062Y-310100D01*
X489689Y-310310D01*
X490237Y-310835D01*
X490472Y-311570D01*
X490315Y-312305D01*
X489924Y-312830D01*
X489454Y-313040D01*
X488670D01*
X487965Y-313355D01*
X487495Y-313985D01*
X487339Y-314720D01*
X487495Y-315455D01*
X487887Y-315980D01*
X488514Y-316295D01*
X489062Y-316400D01*
G01X495205Y-317555D02*
X495519Y-316190D01*
G01X499312Y-310100D02*
X500409Y-316400D01*
X501662Y-310100D01*
X502915Y-316400D01*
X504012Y-310100D01*
G01X509529Y-316400D02*
X506395D01*
Y-310100D01*
X509529D01*
G01X508275Y-313145D02*
X506395D01*
G01X512460Y-316400D02*
Y-310100D01*
X516064Y-316400D01*
Y-310100D01*
G01X525217Y-316400D02*
Y-310100D01*
G01X528507D02*
Y-316400D01*
G01Y-313250D02*
X525217D01*
G01X530812Y-310100D02*
X531909Y-316400D01*
X533162Y-310100D01*
X534415Y-316400D01*
X535512Y-310100D01*
G01X537504Y-316400D02*
X539462Y-310100D01*
X541420Y-316400D01*
G01X540715Y-314195D02*
X538209D01*
G01X550574Y-311150D02*
X551044Y-310520D01*
X551592Y-310205D01*
X552219Y-310100D01*
X553002Y-310310D01*
X553550Y-310835D01*
X553707Y-311465D01*
X553629Y-312095D01*
X553315Y-312620D01*
X551749Y-313670D01*
X551044Y-314405D01*
X550574Y-315455D01*
X550417Y-316400D01*
X553707D01*
G01X556560D02*
Y-310100D01*
X560164Y-316400D01*
Y-310100D01*
G01X562939Y-316400D02*
Y-310100D01*
X564505D01*
X565132Y-310415D01*
X565602Y-310835D01*
X565994Y-311465D01*
X566307Y-312200D01*
X566385Y-313250D01*
X566307Y-314300D01*
X565994Y-315035D01*
X565602Y-315665D01*
X565132Y-316085D01*
X564505Y-316400D01*
X562939D01*
G01X575695D02*
Y-310100D01*
X577654D01*
X578280Y-310415D01*
X578672Y-310835D01*
X578829Y-311675D01*
X578672Y-312515D01*
X578202Y-313040D01*
X577654Y-313355D01*
X575695D01*
G01X577654D02*
X578829Y-316400D01*
G01X581839D02*
Y-310100D01*
X583405D01*
X584032Y-310415D01*
X584502Y-310835D01*
X584894Y-311465D01*
X585207Y-312200D01*
X585285Y-313250D01*
X585207Y-314300D01*
X584894Y-315035D01*
X584502Y-315665D01*
X584032Y-316085D01*
X583405Y-316400D01*
X581839D01*
G01X589862Y-316610D02*
X589705Y-316505D01*
Y-316295D01*
X589862Y-316190D01*
X590019Y-316295D01*
Y-316505D01*
X589862Y-316610D01*
G01X450906Y-49508D02*
X521772D01*
Y80611D01*
X450906D01*
Y35400D01*
G01Y18200D02*
Y-49508D01*
G01X509961Y68800D02*
X462717D01*
Y-37697D01*
X509961D01*
Y68800D01*
G01X462242Y4156D02*
X455942D01*
Y6036D01*
X456257Y6663D01*
X456992Y7133D01*
X457832Y7290D01*
X458672Y7133D01*
X459302Y6741D01*
X459617Y6036D01*
Y4156D01*
G01X462242Y10456D02*
X455942D01*
Y12415D01*
X456257Y13041D01*
X456677Y13433D01*
X457517Y13590D01*
X458357Y13433D01*
X458882Y12963D01*
X459197Y12415D01*
Y10456D01*
G01Y12415D02*
X462242Y13590D01*
G01Y19890D02*
Y16756D01*
X455942D01*
Y19890D01*
G01X458987Y18636D02*
Y16756D01*
G01X461402Y22978D02*
X461927Y23605D01*
X462242Y24310D01*
Y24936D01*
X461927Y25563D01*
X461402Y26033D01*
X460667Y26268D01*
X459932Y26111D01*
X459302Y25720D01*
X458882Y25015D01*
X458672Y24075D01*
X458252Y23526D01*
X457517Y23291D01*
X456782Y23448D01*
X456257Y23840D01*
X455942Y24388D01*
Y24936D01*
X456152Y25485D01*
X456677Y25955D01*
G01X461402Y29278D02*
X461927Y29905D01*
X462242Y30610D01*
Y31236D01*
X461927Y31863D01*
X461402Y32333D01*
X460667Y32568D01*
X459932Y32411D01*
X459302Y32020D01*
X458882Y31315D01*
X458672Y30375D01*
X458252Y29826D01*
X457517Y29591D01*
X456782Y29748D01*
X456257Y30140D01*
X455942Y30688D01*
Y31236D01*
X456152Y31785D01*
X456677Y32255D01*
G01X460142Y36205D02*
Y38241D01*
G01X462242Y42035D02*
X455942D01*
Y45011D01*
G01X458987Y43915D02*
Y42035D01*
G01X455942Y48883D02*
Y50763D01*
G01Y49823D02*
X462242D01*
G01Y48883D02*
Y50763D01*
G01X455942Y56123D02*
X462242D01*
G01X455942Y54321D02*
Y57925D01*
G01X465918Y71382D02*
X466186Y71743D01*
X466416Y71950D01*
X466723Y72053D01*
X466991Y71950D01*
X467183Y71743D01*
X467336Y71433D01*
X467374Y71072D01*
X467336Y70762D01*
X467183Y70452D01*
X466953Y70193D01*
X466684Y70090D01*
X466378Y70193D01*
X466109Y70503D01*
X465956Y70968D01*
X465918Y71485D01*
X465994Y72157D01*
X466109Y72518D01*
X466301Y72880D01*
X466569Y73138D01*
X466838Y73190D01*
X467106Y73087D01*
X467298Y72828D01*
G01X457800Y106400D02*
X456800D01*
Y81300D01*
X457600D01*
G01X458760Y88915D02*
X464960D01*
Y85715D01*
X458760D01*
Y88915D01*
G01Y93215D02*
X464960D01*
Y90015D01*
X458760D01*
Y93215D01*
G01Y97515D02*
X464960D01*
Y94315D01*
X458760D01*
Y97515D01*
G01Y84615D02*
X464960D01*
Y81415D01*
X458760D01*
Y84615D01*
G01Y101815D02*
X464960D01*
Y98615D01*
X458760D01*
Y101815D01*
G01X473312Y85958D02*
X467112D01*
Y89158D01*
X473312D01*
Y85958D01*
G01Y81658D02*
X467112D01*
Y84858D01*
X473312D01*
Y81658D01*
G01X466700Y106400D02*
X468200D01*
Y95200D01*
X506900D01*
Y106400D01*
X508400D01*
G01X458760Y106115D02*
X464960D01*
Y102915D01*
X458760D01*
Y106115D01*
G01X448842Y102754D02*
X448995Y102909D01*
X449110Y103168D01*
X449187Y103529D01*
X449110Y103839D01*
X448957Y104046D01*
X448688Y104201D01*
X447653D01*
Y101101D01*
X448918D01*
X449187Y101308D01*
X449340Y101618D01*
X449417Y101979D01*
X449340Y102341D01*
X449110Y102651D01*
X448842Y102754D01*
X447653D01*
G01X451635Y101101D02*
Y104201D01*
X451175Y103581D01*
G01Y101101D02*
X452095D01*
G01X448347Y126150D02*
Y107162D01*
X524371D01*
X524373Y110814D01*
G01X448347Y188350D02*
Y137350D01*
G01X524371Y200150D02*
Y219170D01*
X448347D01*
Y201050D01*
G01X479862Y-303700D02*
X477342Y-303283D01*
X475137Y-301617D01*
X473247Y-299117D01*
X471987Y-296200D01*
X471357Y-292867D01*
Y-289533D01*
X471987Y-286200D01*
X473247Y-283283D01*
X475137Y-280784D01*
X477342Y-279117D01*
X479862Y-278700D01*
X482382Y-279117D01*
X484587Y-280784D01*
X486477Y-283283D01*
X487737Y-286200D01*
X488367Y-289533D01*
Y-292867D01*
X487737Y-296200D01*
X486477Y-299117D01*
X484587Y-301617D01*
X482382Y-303283D01*
X479862Y-303700D01*
G01X482382Y-297033D02*
X486162Y-303700D01*
G01X499707Y-287034D02*
Y-298700D01*
X500967Y-301617D01*
X502857Y-303283D01*
X505062Y-303700D01*
X507267Y-303283D01*
X509157Y-301617D01*
X510417Y-298700D01*
G01Y-303700D02*
Y-287034D01*
G01X535932Y-303700D02*
Y-287034D01*
G01Y-289950D02*
X534672Y-288284D01*
X532782Y-287450D01*
X530577Y-287034D01*
X528372Y-287867D01*
X526482Y-289533D01*
X525222Y-292034D01*
X524592Y-295367D01*
X525222Y-298700D01*
X526482Y-301201D01*
X528372Y-302867D01*
X530577Y-303700D01*
X532782Y-303283D01*
X534672Y-302034D01*
X535932Y-300367D01*
G01X550107Y-303700D02*
Y-287034D01*
G01Y-291200D02*
X551367Y-289117D01*
X553257Y-287450D01*
X555777Y-287034D01*
X557982Y-287450D01*
X559872Y-289117D01*
X560817Y-292034D01*
Y-303700D01*
G01X580662Y-278700D02*
Y-303700D01*
G01X576252Y-287034D02*
X585072D01*
G01X611532Y-303700D02*
Y-287034D01*
G01Y-289950D02*
X610272Y-288284D01*
X608382Y-287450D01*
X606177Y-287034D01*
X603972Y-287867D01*
X602082Y-289533D01*
X600822Y-292034D01*
X600192Y-295367D01*
X600822Y-298700D01*
X602082Y-301201D01*
X603972Y-302867D01*
X606177Y-303700D01*
X608382Y-303283D01*
X610272Y-302034D01*
X611532Y-300367D01*
G01X482606Y70090D02*
Y73190D01*
X481188Y70968D01*
X483104D01*
G01X473703Y70355D02*
X473933Y70097D01*
X474201Y69942D01*
X474546Y69890D01*
X474891Y69993D01*
X475159Y70200D01*
X475351Y70562D01*
X475389Y70975D01*
X475313Y71388D01*
X475121Y71647D01*
X474853Y71853D01*
X474584Y71905D01*
X474316Y71853D01*
X473971Y71647D01*
X474086Y72990D01*
X475121D01*
G01X489003Y70410D02*
X489233Y70048D01*
X489539Y69842D01*
X489884Y69790D01*
X490191Y69842D01*
X490498Y70100D01*
X490689Y70410D01*
X490728Y70720D01*
X490651Y71082D01*
X490383Y71340D01*
X490114Y71443D01*
X489769D01*
G01X490114D02*
X490344Y71598D01*
X490536Y71857D01*
X490613Y72167D01*
X490536Y72477D01*
X490344Y72735D01*
X489999Y72890D01*
X489654Y72838D01*
X489309Y72632D01*
G01X469883Y103100D02*
Y96800D01*
X473017D01*
G01X475792D02*
X477750Y103100D01*
X479708Y96800D01*
G01X479003Y99005D02*
X476497D01*
G01X482248Y96800D02*
Y103100D01*
X485852Y96800D01*
Y103100D01*
G01X490350Y96800D02*
Y103100D01*
X489410Y101840D01*
G01Y96800D02*
X491290D01*
G01X494300Y98900D02*
X495083Y101000D01*
X495867D01*
X497433Y96800D01*
X498217D01*
X499000Y98900D01*
G01X501462Y102050D02*
X501932Y102680D01*
X502480Y102995D01*
X503107Y103100D01*
X503890Y102890D01*
X504438Y102365D01*
X504595Y101735D01*
X504517Y101105D01*
X504203Y100580D01*
X502637Y99530D01*
X501932Y98795D01*
X501462Y97745D01*
X501305Y96800D01*
X504595D01*
G01X508300Y81500D02*
X480400D01*
Y81400D01*
G01X490500Y95100D02*
X490400D01*
Y89600D01*
X496700D01*
Y95100D01*
G01X476030Y81753D02*
Y87953D01*
X479230D01*
Y81753D01*
X476030D01*
G01X484858Y88733D02*
Y82533D01*
X481658D01*
Y88733D01*
X484858D01*
G01X473167Y93558D02*
X479367D01*
Y90358D01*
X473167D01*
Y93558D01*
G01X485958Y82533D02*
Y88733D01*
X489158D01*
Y82533D01*
X485958D01*
G01X511588Y3499D02*
X512546Y6599D01*
X513504Y3499D01*
G01X513159Y4584D02*
X511933D01*
G01X513426Y20613D02*
X513196Y20768D01*
X512928Y20871D01*
X512621D01*
X512276Y20716D01*
X512008Y20458D01*
X511816Y20148D01*
X511663Y19631D01*
X511625Y19166D01*
X511701Y18701D01*
X511816Y18391D01*
X512046Y18081D01*
X512315Y17874D01*
X512583Y17771D01*
X512851D01*
X513120Y17874D01*
X513350Y18029D01*
X513541Y18236D01*
G01X513090Y13636D02*
X513243Y13791D01*
X513358Y14050D01*
X513435Y14411D01*
X513358Y14721D01*
X513205Y14928D01*
X512936Y15083D01*
X511901D01*
Y11983D01*
X513166D01*
X513435Y12190D01*
X513588Y12500D01*
X513665Y12861D01*
X513588Y13223D01*
X513358Y13533D01*
X513090Y13636D01*
X511901D01*
G01X513350Y28647D02*
X511816D01*
Y31747D01*
X513350D01*
G01X512736Y30249D02*
X511816D01*
G01X511940Y23259D02*
Y26359D01*
X512706D01*
X513013Y26204D01*
X513243Y25997D01*
X513435Y25687D01*
X513588Y25326D01*
X513626Y24809D01*
X513588Y24292D01*
X513435Y23931D01*
X513243Y23621D01*
X513013Y23414D01*
X512706Y23259D01*
X511940D01*
G01X512055Y34135D02*
Y37235D01*
X513511D01*
G01X512975Y35737D02*
X512055D01*
G01X512613Y41673D02*
X513380D01*
Y40743D01*
X513150Y40433D01*
X512881Y40226D01*
X512498Y40123D01*
X512115Y40226D01*
X511846Y40433D01*
X511616Y40743D01*
X511463Y41105D01*
X511386Y41518D01*
Y41880D01*
X511463Y42190D01*
X511616Y42551D01*
X511846Y42861D01*
X512076Y43068D01*
X512383Y43223D01*
X512651D01*
X512958Y43120D01*
X513188Y42913D01*
G01X513322Y48288D02*
Y45188D01*
G01X511712D02*
Y48288D01*
G01Y46738D02*
X513322D01*
G01X512977Y50700D02*
X512057D01*
G01X512517D02*
Y53800D01*
G01X512977D02*
X512057D01*
G01X496718Y72673D02*
X496948Y72983D01*
X497216Y73138D01*
X497523Y73190D01*
X497906Y73087D01*
X498174Y72828D01*
X498251Y72518D01*
X498213Y72208D01*
X498059Y71950D01*
X497293Y71433D01*
X496948Y71072D01*
X496718Y70555D01*
X496641Y70090D01*
X498251D01*
G01X506246Y69890D02*
Y72990D01*
X505786Y72370D01*
G01Y69890D02*
X506706D01*
G01X492392Y90400D02*
X493350Y93500D01*
X494308Y90400D01*
G01X493963Y91485D02*
X492737D01*
G01X515312Y89961D02*
X509112D01*
Y93161D01*
X515312D01*
Y89961D01*
G01Y94261D02*
X509112D01*
Y97461D01*
X515312D01*
Y94261D01*
G01X497842Y88733D02*
Y82533D01*
X494642D01*
Y88733D01*
X497842D01*
G01X498958Y82533D02*
Y88733D01*
X502158D01*
Y82533D01*
X498958D01*
G01X503242D02*
Y88733D01*
X506442D01*
Y82533D01*
X503242D01*
G01X509288Y84842D02*
X515488D01*
Y81642D01*
X509288D01*
Y84842D01*
G01Y89042D02*
X515488D01*
Y85842D01*
X509288D01*
Y89042D01*
G01X515312Y98561D02*
X509112D01*
Y101761D01*
X515312D01*
Y98561D01*
G01Y102861D02*
X509112D01*
Y106061D01*
X515312D01*
Y102861D01*
G01X492424Y103437D02*
X492616Y103127D01*
X492846Y102920D01*
X493114Y102817D01*
X493421Y102920D01*
X493651Y103127D01*
X493881Y103437D01*
X493958Y103850D01*
Y105917D01*
G01X495563Y105400D02*
X495793Y105710D01*
X496061Y105865D01*
X496368Y105917D01*
X496751Y105814D01*
X497019Y105555D01*
X497096Y105245D01*
X497058Y104935D01*
X496904Y104677D01*
X496138Y104160D01*
X495793Y103799D01*
X495563Y103282D01*
X495486Y102817D01*
X497096D01*
G01X498663Y105400D02*
X498893Y105710D01*
X499161Y105865D01*
X499468Y105917D01*
X499851Y105814D01*
X500119Y105555D01*
X500196Y105245D01*
X500158Y104935D01*
X500004Y104677D01*
X499238Y104160D01*
X498893Y103799D01*
X498663Y103282D01*
X498586Y102817D01*
X500196D01*
G01X533791Y4993D02*
X533636Y4763D01*
X533533Y4495D01*
Y4188D01*
X533688Y3843D01*
X533946Y3575D01*
X534256Y3383D01*
X534773Y3230D01*
X535238Y3192D01*
X535703Y3268D01*
X536013Y3383D01*
X536323Y3613D01*
X536530Y3882D01*
X536633Y4150D01*
Y4418D01*
X536530Y4687D01*
X536375Y4917D01*
X536168Y5108D01*
G01X534050Y6522D02*
X533740Y6752D01*
X533585Y7020D01*
X533533Y7327D01*
X533636Y7710D01*
X533895Y7978D01*
X534205Y8055D01*
X534515Y8017D01*
X534773Y7863D01*
X535290Y7097D01*
X535651Y6752D01*
X536168Y6522D01*
X536633Y6445D01*
Y8055D01*
G01X534050Y9622D02*
X533740Y9852D01*
X533585Y10120D01*
X533533Y10427D01*
X533636Y10810D01*
X533895Y11078D01*
X534205Y11155D01*
X534515Y11117D01*
X534773Y10963D01*
X535290Y10197D01*
X535651Y9852D01*
X536168Y9622D01*
X536633Y9545D01*
Y11155D01*
G01X529491Y5393D02*
X529336Y5163D01*
X529233Y4895D01*
Y4588D01*
X529388Y4243D01*
X529646Y3975D01*
X529956Y3783D01*
X530473Y3630D01*
X530938Y3592D01*
X531403Y3668D01*
X531713Y3783D01*
X532023Y4013D01*
X532230Y4282D01*
X532333Y4550D01*
Y4818D01*
X532230Y5087D01*
X532075Y5317D01*
X531868Y5508D01*
G01X529750Y6922D02*
X529440Y7152D01*
X529285Y7420D01*
X529233Y7727D01*
X529336Y8110D01*
X529595Y8378D01*
X529905Y8455D01*
X530215Y8417D01*
X530473Y8263D01*
X530990Y7497D01*
X531351Y7152D01*
X531868Y6922D01*
X532333Y6845D01*
Y8455D01*
G01Y10750D02*
X529233D01*
X529853Y10290D01*
G01X532333D02*
Y11210D01*
G01X526181Y2959D02*
X526491Y3151D01*
X526698Y3381D01*
X526801Y3649D01*
X526698Y3956D01*
X526491Y4186D01*
X526181Y4416D01*
X525768Y4493D01*
X523701D01*
G01X524218Y6098D02*
X523908Y6328D01*
X523753Y6596D01*
X523701Y6903D01*
X523804Y7286D01*
X524063Y7554D01*
X524373Y7631D01*
X524683Y7593D01*
X524941Y7439D01*
X525458Y6673D01*
X525819Y6328D01*
X526336Y6098D01*
X526801Y6021D01*
Y7631D01*
G01Y10386D02*
X523701D01*
X525923Y8968D01*
Y10884D01*
G01X527092Y20900D02*
X529050Y27200D01*
X531008Y20900D01*
G01X530303Y23105D02*
X527797D01*
G01X534410Y27200D02*
X536290D01*
G01X535350D02*
Y20900D01*
G01X534410D02*
X536290D01*
G01X540083D02*
Y27200D01*
X542042D01*
X542668Y26885D01*
X543060Y26465D01*
X543217Y25625D01*
X543060Y24785D01*
X542590Y24260D01*
X542042Y23945D01*
X540083D01*
G01X542042D02*
X543217Y20900D01*
G01X545913D02*
Y27200D01*
X547950Y21950D01*
X549987Y27200D01*
Y20900D01*
G01X552292D02*
X554250Y27200D01*
X556208Y20900D01*
G01X555503Y23105D02*
X552997D01*
G01X558905Y20900D02*
X562195Y27200D01*
G01X558905D02*
X562195Y20900D01*
G01X527283Y19200D02*
Y12900D01*
X530417D01*
G01X533192D02*
X535150Y19200D01*
X537108Y12900D01*
G01X536403Y15105D02*
X533897D01*
G01X539648Y12900D02*
Y19200D01*
X543252Y12900D01*
Y19200D01*
G01X523500Y17698D02*
X517186D01*
G01D02*
Y235414D01*
X604784D01*
Y17698D01*
X553200D01*
G01X540536Y29509D02*
X528997D01*
Y223603D01*
X592973D01*
G01X516100Y106500D02*
X516400D01*
Y89000D01*
X516300D01*
G01X516500Y86100D02*
Y81300D01*
X516100D01*
G01X520498Y104370D02*
X520651Y104525D01*
X520766Y104784D01*
X520843Y105145D01*
X520766Y105455D01*
X520613Y105662D01*
X520344Y105817D01*
X519309D01*
Y102717D01*
X520574D01*
X520843Y102924D01*
X520996Y103234D01*
X521073Y103595D01*
X520996Y103957D01*
X520766Y104267D01*
X520498Y104370D01*
X519309D01*
G01X523214Y102717D02*
X523291Y103389D01*
X523406Y103957D01*
X523559Y104474D01*
X523751Y105042D01*
X524058Y105817D01*
X522524D01*
G01X524378Y120427D02*
X524405Y173870D01*
X524371Y176650D01*
G01X528383Y135133D02*
X525283Y136091D01*
X528383Y137049D01*
G01X527298Y136704D02*
Y135478D01*
G01X525800Y138463D02*
X525490Y138693D01*
X525335Y138961D01*
X525283Y139268D01*
X525386Y139651D01*
X525645Y139919D01*
X525955Y139996D01*
X526265Y139958D01*
X526523Y139804D01*
X527040Y139038D01*
X527401Y138693D01*
X527918Y138463D01*
X528383Y138386D01*
Y139996D01*
G01X526830Y124998D02*
X526675Y125151D01*
X526416Y125266D01*
X526055Y125343D01*
X525745Y125266D01*
X525538Y125113D01*
X525383Y124844D01*
Y123809D01*
X528483D01*
Y125074D01*
X528276Y125343D01*
X527966Y125496D01*
X527605Y125573D01*
X527243Y125496D01*
X526933Y125266D01*
X526830Y124998D01*
Y123809D01*
G01X528483Y127791D02*
X528431Y128059D01*
X528276Y128366D01*
X528018Y128558D01*
X527656Y128634D01*
X527295Y128558D01*
X526985Y128328D01*
X526830Y127983D01*
Y127599D01*
X526726Y127369D01*
X526468Y127178D01*
X526106Y127101D01*
X525745Y127216D01*
X525486Y127484D01*
X525383Y127791D01*
X525486Y128098D01*
X525745Y128366D01*
X526106Y128481D01*
X526468Y128404D01*
X526726Y128213D01*
X526830Y127983D01*
Y127599D01*
X526985Y127254D01*
X527295Y127024D01*
X527656Y126948D01*
X528018Y127024D01*
X528276Y127216D01*
X528431Y127523D01*
X528483Y127791D01*
G01X528183Y158133D02*
X525083Y159091D01*
X528183Y160049D01*
G01X527098Y159704D02*
Y158478D01*
G01X528183Y162191D02*
X525083D01*
X525703Y161731D01*
G01X528183D02*
Y162651D01*
G01X524371Y176650D02*
Y189050D01*
G01X547170Y2667D02*
X547677Y2250D01*
X548247Y2000D01*
X548753D01*
X549260Y2250D01*
X549640Y2667D01*
X549830Y3250D01*
X549703Y3833D01*
X549387Y4333D01*
X548817Y4667D01*
X548057Y4833D01*
X547613Y5167D01*
X547423Y5750D01*
X547550Y6333D01*
X547867Y6750D01*
X548310Y7000D01*
X548753D01*
X549197Y6833D01*
X549577Y6417D01*
G01X552397Y2000D02*
Y7000D01*
X554803D01*
G01X553917Y4583D02*
X552397D01*
G01X557433Y2000D02*
Y7000D01*
X558953D01*
X559460Y6750D01*
X559840Y6167D01*
X559967Y5500D01*
X559840Y4833D01*
X559523Y4333D01*
X558953Y4083D01*
X557433D01*
G01X563103Y3667D02*
X564623D01*
G01X563800Y4750D02*
Y2583D01*
G01X537991Y5093D02*
X537836Y4863D01*
X537733Y4595D01*
Y4288D01*
X537888Y3943D01*
X538146Y3675D01*
X538456Y3483D01*
X538973Y3330D01*
X539438Y3292D01*
X539903Y3368D01*
X540213Y3483D01*
X540523Y3713D01*
X540730Y3982D01*
X540833Y4250D01*
Y4518D01*
X540730Y4787D01*
X540575Y5017D01*
X540368Y5208D01*
G01X540833Y7350D02*
X537733D01*
X538353Y6890D01*
G01X540833D02*
Y7810D01*
G01Y10450D02*
X540781Y10718D01*
X540626Y11025D01*
X540368Y11217D01*
X540006Y11293D01*
X539645Y11217D01*
X539335Y10987D01*
X539180Y10642D01*
Y10258D01*
X539076Y10028D01*
X538818Y9837D01*
X538456Y9760D01*
X538095Y9875D01*
X537836Y10143D01*
X537733Y10450D01*
X537836Y10757D01*
X538095Y11025D01*
X538456Y11140D01*
X538818Y11063D01*
X539076Y10872D01*
X539180Y10642D01*
Y10258D01*
X539335Y9913D01*
X539645Y9683D01*
X540006Y9607D01*
X540368Y9683D01*
X540626Y9875D01*
X540781Y10182D01*
X540833Y10450D01*
G01X542591Y5093D02*
X542436Y4863D01*
X542333Y4595D01*
Y4288D01*
X542488Y3943D01*
X542746Y3675D01*
X543056Y3483D01*
X543573Y3330D01*
X544038Y3292D01*
X544503Y3368D01*
X544813Y3483D01*
X545123Y3713D01*
X545330Y3982D01*
X545433Y4250D01*
Y4518D01*
X545330Y4787D01*
X545175Y5017D01*
X544968Y5208D01*
G01X545433Y7350D02*
X542333D01*
X542953Y6890D01*
G01X545433D02*
Y7810D01*
G01Y10373D02*
X544761Y10450D01*
X544193Y10565D01*
X543676Y10718D01*
X543108Y10910D01*
X542333Y11217D01*
Y9683D01*
G01X550522Y16813D02*
Y14591D01*
X550675Y14126D01*
X550982Y13816D01*
X551365Y13713D01*
X551748Y13816D01*
X552055Y14126D01*
X552208Y14591D01*
Y16813D01*
G01X553622Y14178D02*
X553852Y13920D01*
X554120Y13765D01*
X554465Y13713D01*
X554810Y13816D01*
X555078Y14023D01*
X555270Y14385D01*
X555308Y14798D01*
X555232Y15211D01*
X555040Y15470D01*
X554772Y15676D01*
X554503Y15728D01*
X554235Y15676D01*
X553890Y15470D01*
X554005Y16813D01*
X555040D01*
G01X545036Y33446D02*
X546044D01*
Y29509D01*
X543636D01*
G01X549704Y32610D02*
X546604D01*
X547224Y32150D01*
G01X549704D02*
Y33070D01*
G01Y35710D02*
X546604D01*
X547224Y35250D01*
G01X549704D02*
Y36170D01*
G01X546085Y42087D02*
X539331D01*
G01D02*
Y53154D01*
G01X582836Y33446D02*
X585099D01*
Y90532D01*
X536871D01*
Y33446D01*
X539136D01*
G01X539331Y60154D02*
Y71221D01*
G01D02*
X544485D01*
G01X543804Y78410D02*
X540704D01*
X541324Y77950D01*
G01X543804D02*
Y78870D01*
G01X540704Y81510D02*
X540807Y81203D01*
X541066Y80973D01*
X541376Y80820D01*
X541789Y80705D01*
X542254Y80667D01*
X542719Y80705D01*
X543132Y80820D01*
X543442Y80973D01*
X543701Y81203D01*
X543804Y81510D01*
X543701Y81817D01*
X543442Y82047D01*
X543132Y82200D01*
X542719Y82315D01*
X542254Y82353D01*
X541789Y82315D01*
X541376Y82200D01*
X541066Y82047D01*
X540807Y81817D01*
X540704Y81510D01*
G01X569793Y6183D02*
X569413Y6433D01*
X568970Y6600D01*
X568463D01*
X567893Y6350D01*
X567450Y5933D01*
X567133Y5433D01*
X566880Y4600D01*
X566817Y3850D01*
X566943Y3100D01*
X567133Y2600D01*
X567513Y2100D01*
X567957Y1767D01*
X568400Y1600D01*
X568843D01*
X569287Y1767D01*
X569667Y2017D01*
X569983Y2350D01*
G01X573500Y1600D02*
X572993Y1683D01*
X572550Y2017D01*
X572170Y2517D01*
X571917Y3100D01*
X571790Y3767D01*
Y4433D01*
X571917Y5100D01*
X572170Y5683D01*
X572550Y6183D01*
X572993Y6517D01*
X573500Y6600D01*
X574007Y6517D01*
X574450Y6183D01*
X574830Y5683D01*
X575083Y5100D01*
X575210Y4433D01*
Y3767D01*
X575083Y3100D01*
X574830Y2517D01*
X574450Y2017D01*
X574007Y1683D01*
X573500Y1600D01*
G01X577143D02*
Y6600D01*
X580057Y1600D01*
Y6600D01*
G01X582243Y1600D02*
Y6600D01*
X585157Y1600D01*
Y6600D01*
G01X587597Y5767D02*
X587977Y6267D01*
X588420Y6517D01*
X588927Y6600D01*
X589560Y6433D01*
X590003Y6017D01*
X590130Y5517D01*
X590067Y5017D01*
X589813Y4600D01*
X588547Y3767D01*
X587977Y3183D01*
X587597Y2350D01*
X587470Y1600D01*
X590130D01*
G01X577821Y23282D02*
X577511Y23512D01*
X577356Y23780D01*
X577304Y24087D01*
X577407Y24470D01*
X577666Y24738D01*
X577976Y24815D01*
X578286Y24777D01*
X578544Y24623D01*
X579061Y23857D01*
X579422Y23512D01*
X579939Y23282D01*
X580404Y23205D01*
Y24815D01*
G01X577304Y27110D02*
X577407Y26803D01*
X577666Y26573D01*
X577976Y26420D01*
X578389Y26305D01*
X578854Y26267D01*
X579319Y26305D01*
X579732Y26420D01*
X580042Y26573D01*
X580301Y26803D01*
X580404Y27110D01*
X580301Y27417D01*
X580042Y27647D01*
X579732Y27800D01*
X579319Y27915D01*
X578854Y27953D01*
X578389Y27915D01*
X577976Y27800D01*
X577666Y27647D01*
X577407Y27417D01*
X577304Y27110D01*
G01X592973Y223603D02*
Y29509D01*
X581336D01*
G01X578336D02*
X575926D01*
Y33446D01*
X576936D01*
G01X570100Y8900D02*
Y15100D01*
X573300D01*
Y8900D01*
X570100D01*
G01X573200Y12000D02*
X570200D01*
G01X565700Y8900D02*
Y15100D01*
X568900D01*
Y8900D01*
X565700D01*
G01X568800Y12000D02*
X565800D01*
G01X561200Y8900D02*
Y15100D01*
X564400D01*
Y8900D01*
X561200D01*
G01X564300Y12000D02*
X561300D01*
G01X574500Y8900D02*
Y15100D01*
X577700D01*
Y8900D01*
X574500D01*
G01X577600Y12000D02*
X574600D01*
G01X582639Y42087D02*
X577485D01*
G01X582639D02*
Y54154D01*
G01X575885Y71221D02*
X582639D01*
G01Y59154D02*
Y71221D01*
G01X577084Y77896D02*
Y80996D01*
X576624Y80376D01*
G01Y77896D02*
X577544D01*
G01X591082Y41850D02*
Y-127559D01*
X633012D01*
Y83189D01*
X591082D01*
Y41850D01*
G01Y-9842D02*
X633012D01*
G01X589251Y25609D02*
Y28709D01*
X588791Y28089D01*
G01Y25609D02*
X589711D01*
G01X605600Y155700D02*
X605800D01*
Y87400D01*
X627300D01*
Y104400D01*
X625200D01*
Y127200D01*
X631000D01*
Y157400D01*
X626100D01*
Y176400D01*
X620400D01*
G01X602086Y104705D02*
X595786D01*
Y106585D01*
X596101Y107212D01*
X596836Y107682D01*
X597676Y107839D01*
X598516Y107682D01*
X599146Y107290D01*
X599461Y106585D01*
Y104705D01*
G01X602086Y111005D02*
X595786D01*
Y112964D01*
X596101Y113590D01*
X596521Y113982D01*
X597361Y114139D01*
X598201Y113982D01*
X598726Y113512D01*
X599041Y112964D01*
Y111005D01*
G01Y112964D02*
X602086Y114139D01*
G01Y120439D02*
Y117305D01*
X595786D01*
Y120439D01*
G01X598831Y119185D02*
Y117305D01*
G01X601246Y123527D02*
X601771Y124154D01*
X602086Y124859D01*
Y125485D01*
X601771Y126112D01*
X601246Y126582D01*
X600511Y126817D01*
X599776Y126660D01*
X599146Y126269D01*
X598726Y125564D01*
X598516Y124624D01*
X598096Y124075D01*
X597361Y123840D01*
X596626Y123997D01*
X596101Y124389D01*
X595786Y124937D01*
Y125485D01*
X595996Y126034D01*
X596521Y126504D01*
G01X601246Y129827D02*
X601771Y130454D01*
X602086Y131159D01*
Y131785D01*
X601771Y132412D01*
X601246Y132882D01*
X600511Y133117D01*
X599776Y132960D01*
X599146Y132569D01*
X598726Y131864D01*
X598516Y130924D01*
X598096Y130375D01*
X597361Y130140D01*
X596626Y130297D01*
X596101Y130689D01*
X595786Y131237D01*
Y131785D01*
X595996Y132334D01*
X596521Y132804D01*
G01X599986Y136754D02*
Y138790D01*
G01X602086Y142584D02*
X595786D01*
Y145560D01*
G01X598831Y144464D02*
Y142584D01*
G01X595786Y149432D02*
Y151312D01*
G01Y150372D02*
X602086D01*
G01Y149432D02*
Y151312D01*
G01X595786Y156672D02*
X602086D01*
G01X595786Y154870D02*
Y158474D01*
G01X609800Y173700D02*
X605600D01*
Y165800D01*
G01Y166200D02*
Y159700D01*
G01X606910Y147521D02*
Y150621D01*
X606450Y150001D01*
G01Y147521D02*
X607370D01*
G01X612940Y93539D02*
X606740D01*
Y96739D01*
X612940D01*
Y93539D01*
G01Y98557D02*
X606740D01*
Y101757D01*
X612940D01*
Y98557D01*
G01Y88557D02*
X606740D01*
Y91757D01*
X612940D01*
Y88557D01*
G01X618088Y91757D02*
X624288D01*
Y88557D01*
X618088D01*
Y91757D01*
G01Y96739D02*
X624288D01*
Y93539D01*
X618088D01*
Y96739D01*
G01Y101757D02*
X624288D01*
Y98557D01*
X618088D01*
Y101757D01*
G01X630349Y95077D02*
X630194Y95230D01*
X629935Y95345D01*
X629574Y95422D01*
X629264Y95345D01*
X629057Y95192D01*
X628902Y94923D01*
Y93888D01*
X632002D01*
Y95153D01*
X631795Y95422D01*
X631485Y95575D01*
X631124Y95652D01*
X630762Y95575D01*
X630452Y95345D01*
X630349Y95077D01*
Y93888D01*
G01X632002Y97870D02*
X628902D01*
X629522Y97410D01*
G01X632002D02*
Y98330D01*
G01X631382Y100127D02*
X631744Y100357D01*
X631950Y100663D01*
X632002Y101008D01*
X631950Y101315D01*
X631692Y101622D01*
X631382Y101813D01*
X631072Y101852D01*
X630710Y101775D01*
X630452Y101507D01*
X630349Y101238D01*
Y100893D01*
G01Y101238D02*
X630194Y101468D01*
X629935Y101660D01*
X629625Y101737D01*
X629315Y101660D01*
X629057Y101468D01*
X628902Y101123D01*
X628954Y100778D01*
X629160Y100433D01*
G01X609630Y84637D02*
X609822Y84327D01*
X610052Y84120D01*
X610320Y84017D01*
X610627Y84120D01*
X610857Y84327D01*
X611087Y84637D01*
X611164Y85050D01*
Y87117D01*
G01X613497Y84017D02*
Y87117D01*
X613037Y86497D01*
G01Y84017D02*
X613957D01*
G01X615869Y86600D02*
X616099Y86910D01*
X616367Y87065D01*
X616674Y87117D01*
X617057Y87014D01*
X617325Y86755D01*
X617402Y86445D01*
X617364Y86135D01*
X617210Y85877D01*
X616444Y85360D01*
X616099Y84999D01*
X615869Y84482D01*
X615792Y84017D01*
X617402D01*
G01X612940Y103557D02*
X606740D01*
Y106757D01*
X612940D01*
Y103557D01*
G01X618088Y106757D02*
X624288D01*
Y103557D01*
X618088D01*
Y106757D01*
G01X631883Y114312D02*
X628783Y115270D01*
X631883Y116228D01*
G01X630798Y115883D02*
Y114657D01*
G01X631883Y118370D02*
X628783D01*
X629403Y117910D01*
G01X631883D02*
Y118830D01*
G01X631263Y120627D02*
X631625Y120857D01*
X631831Y121163D01*
X631883Y121508D01*
X631831Y121815D01*
X631573Y122122D01*
X631263Y122313D01*
X630953Y122352D01*
X630591Y122275D01*
X630333Y122007D01*
X630230Y121738D01*
Y121393D01*
G01Y121738D02*
X630075Y121968D01*
X629816Y122160D01*
X629506Y122237D01*
X629196Y122160D01*
X628938Y121968D01*
X628783Y121623D01*
X628835Y121278D01*
X629041Y120933D01*
G01X627668Y109138D02*
X628435D01*
Y108208D01*
X628205Y107898D01*
X627936Y107691D01*
X627553Y107588D01*
X627170Y107691D01*
X626901Y107898D01*
X626671Y108208D01*
X626518Y108570D01*
X626441Y108983D01*
Y109345D01*
X626518Y109655D01*
X626671Y110016D01*
X626901Y110326D01*
X627131Y110533D01*
X627438Y110688D01*
X627706D01*
X628013Y110585D01*
X628243Y110378D01*
G01X629695Y108208D02*
X629925Y107846D01*
X630231Y107640D01*
X630576Y107588D01*
X630883Y107640D01*
X631190Y107898D01*
X631381Y108208D01*
X631420Y108518D01*
X631343Y108880D01*
X631075Y109138D01*
X630806Y109241D01*
X630461D01*
G01X630806D02*
X631036Y109396D01*
X631228Y109655D01*
X631305Y109965D01*
X631228Y110275D01*
X631036Y110533D01*
X630691Y110688D01*
X630346Y110636D01*
X630001Y110430D01*
G01X606900Y116858D02*
Y123658D01*
X621900D01*
Y116858D01*
X606900D01*
G01Y108758D02*
Y115558D01*
X621900D01*
Y108758D01*
X606900D01*
G01X609207Y133200D02*
Y136300D01*
X609973D01*
X610280Y136145D01*
X610510Y135938D01*
X610702Y135628D01*
X610855Y135267D01*
X610893Y134750D01*
X610855Y134233D01*
X610702Y133872D01*
X610510Y133562D01*
X610280Y133355D01*
X609973Y133200D01*
X609207D01*
G01X606100Y138800D02*
X612500D01*
Y131700D01*
X606000D01*
G01X607930Y153116D02*
X624469D01*
Y144848D01*
X607930D01*
Y153116D01*
G01X621249Y135600D02*
X614649D01*
G01X621249Y142600D02*
X614649D01*
G01X621249Y127600D02*
X614649D01*
G01X614549D02*
Y142600D01*
G01X621249Y134600D02*
X614649D01*
G01X621349Y142600D02*
Y127600D01*
G01X629473Y135600D02*
X622873D01*
G01X629473Y142600D02*
X622873D01*
G01X629473Y127600D02*
X622873D01*
G01X622773D02*
Y142600D01*
G01X629473Y134600D02*
X622873D01*
G01X629068Y125061D02*
X629835D01*
Y124131D01*
X629605Y123821D01*
X629336Y123614D01*
X628953Y123511D01*
X628570Y123614D01*
X628301Y123821D01*
X628071Y124131D01*
X627918Y124493D01*
X627841Y124906D01*
Y125268D01*
X627918Y125578D01*
X628071Y125939D01*
X628301Y126249D01*
X628531Y126456D01*
X628838Y126611D01*
X629106D01*
X629413Y126508D01*
X629643Y126301D01*
G01X631210Y126094D02*
X631440Y126404D01*
X631708Y126559D01*
X632015Y126611D01*
X632398Y126508D01*
X632666Y126249D01*
X632743Y125939D01*
X632705Y125629D01*
X632551Y125371D01*
X631785Y124854D01*
X631440Y124493D01*
X631210Y123976D01*
X631133Y123511D01*
X632743D01*
G01X627282Y151704D02*
X627512Y152014D01*
X627780Y152169D01*
X628087Y152221D01*
X628470Y152118D01*
X628738Y151859D01*
X628815Y151549D01*
X628777Y151239D01*
X628623Y150981D01*
X627857Y150464D01*
X627512Y150103D01*
X627282Y149586D01*
X627205Y149121D01*
X628815D01*
G01X622777Y166868D02*
X623007Y167178D01*
X623275Y167333D01*
X623582Y167385D01*
X623965Y167282D01*
X624233Y167023D01*
X624310Y166713D01*
X624272Y166403D01*
X624118Y166145D01*
X623352Y165628D01*
X623007Y165267D01*
X622777Y164750D01*
X622700Y164285D01*
X624310D01*
G01X607605Y163585D02*
Y166685D01*
X607145Y166065D01*
G01Y163585D02*
X608065D01*
G01X608035Y162752D02*
X624574D01*
Y154484D01*
X608035D01*
Y162752D01*
G01X628268Y167794D02*
X629035D01*
Y166864D01*
X628805Y166554D01*
X628536Y166347D01*
X628153Y166244D01*
X627770Y166347D01*
X627501Y166554D01*
X627271Y166864D01*
X627118Y167226D01*
X627041Y167639D01*
Y168001D01*
X627118Y168311D01*
X627271Y168672D01*
X627501Y168982D01*
X627731Y169189D01*
X628038Y169344D01*
X628306D01*
X628613Y169241D01*
X628843Y169034D01*
G01X631138Y166244D02*
Y169344D01*
X630678Y168724D01*
G01Y166244D02*
X631598D01*
G01X609436Y186119D02*
X609746Y186311D01*
X609953Y186541D01*
X610056Y186809D01*
X609953Y187116D01*
X609746Y187346D01*
X609436Y187576D01*
X609023Y187653D01*
X606956D01*
G01X610056Y189986D02*
X606956D01*
X607576Y189526D01*
G01X610056D02*
Y190446D01*
G01X608764Y192358D02*
X608403Y192626D01*
X608196Y192856D01*
X608093Y193163D01*
X608196Y193431D01*
X608403Y193623D01*
X608713Y193776D01*
X609074Y193814D01*
X609384Y193776D01*
X609694Y193623D01*
X609953Y193393D01*
X610056Y193124D01*
X609953Y192818D01*
X609643Y192549D01*
X609178Y192396D01*
X608661Y192358D01*
X607989Y192434D01*
X607628Y192549D01*
X607266Y192741D01*
X607008Y193009D01*
X606956Y193278D01*
X607059Y193546D01*
X607318Y193738D01*
G01X628889Y180145D02*
X631111D01*
X631576Y180298D01*
X631886Y180605D01*
X631989Y180988D01*
X631886Y181371D01*
X631576Y181678D01*
X631111Y181831D01*
X628889D01*
G01X631989Y184088D02*
X628889D01*
X629509Y183628D01*
G01X631989D02*
Y184548D01*
G01X628889Y187188D02*
X628992Y186881D01*
X629251Y186651D01*
X629561Y186498D01*
X629974Y186383D01*
X630439Y186345D01*
X630904Y186383D01*
X631317Y186498D01*
X631627Y186651D01*
X631886Y186881D01*
X631989Y187188D01*
X631886Y187495D01*
X631627Y187725D01*
X631317Y187878D01*
X630904Y187993D01*
X630439Y188031D01*
X629974Y187993D01*
X629561Y187878D01*
X629251Y187725D01*
X628992Y187495D01*
X628889Y187188D01*
G01X651212Y-283400D02*
Y-291400D01*
X655212D01*
G01X663012D02*
Y-286067D01*
G01Y-287000D02*
X662612Y-286467D01*
X662012Y-286200D01*
X661312Y-286067D01*
X660612Y-286333D01*
X660012Y-286867D01*
X659612Y-287667D01*
X659412Y-288733D01*
X659612Y-289800D01*
X660012Y-290600D01*
X660612Y-291133D01*
X661312Y-291400D01*
X662012Y-291267D01*
X662612Y-290867D01*
X663012Y-290334D01*
G01X667112Y-293800D02*
X667712Y-294067D01*
X668512Y-293800D01*
X669012Y-293267D01*
X669412Y-292600D01*
X670012Y-290467D01*
X671312Y-286067D01*
G01X668112D02*
X670012Y-290467D01*
G01X675712Y-287800D02*
X678912D01*
X678612Y-286867D01*
X678112Y-286333D01*
X677412Y-286067D01*
X676712Y-286200D01*
X676112Y-286600D01*
X675712Y-287533D01*
X675512Y-288334D01*
Y-289133D01*
X675712Y-289933D01*
X676212Y-290733D01*
X676812Y-291267D01*
X677512Y-291400D01*
X678212Y-291133D01*
X678912Y-290334D01*
G01X683812Y-291400D02*
Y-286067D01*
G01Y-287133D02*
X684312Y-286600D01*
X684812Y-286200D01*
X685512Y-286067D01*
X686012Y-286200D01*
X686612Y-286600D01*
G01X633425Y-49508D02*
X704291D01*
Y80611D01*
X633425D01*
Y-49508D01*
G01X692480Y68800D02*
X645236D01*
Y-37697D01*
X692480D01*
Y68800D01*
G01X643123Y9456D02*
X636823D01*
Y11336D01*
X637138Y11963D01*
X637873Y12433D01*
X638713Y12590D01*
X639553Y12433D01*
X640183Y12041D01*
X640498Y11336D01*
Y9456D01*
G01X643123Y15756D02*
X636823D01*
Y17715D01*
X637138Y18341D01*
X637558Y18733D01*
X638398Y18890D01*
X639238Y18733D01*
X639763Y18263D01*
X640078Y17715D01*
Y15756D01*
G01Y17715D02*
X643123Y18890D01*
G01Y25190D02*
Y22056D01*
X636823D01*
Y25190D01*
G01X639868Y23936D02*
Y22056D01*
G01X642283Y28278D02*
X642808Y28905D01*
X643123Y29610D01*
Y30236D01*
X642808Y30863D01*
X642283Y31333D01*
X641548Y31568D01*
X640813Y31411D01*
X640183Y31020D01*
X639763Y30315D01*
X639553Y29375D01*
X639133Y28826D01*
X638398Y28591D01*
X637663Y28748D01*
X637138Y29140D01*
X636823Y29688D01*
Y30236D01*
X637033Y30785D01*
X637558Y31255D01*
G01X642283Y34578D02*
X642808Y35205D01*
X643123Y35910D01*
Y36536D01*
X642808Y37163D01*
X642283Y37633D01*
X641548Y37868D01*
X640813Y37711D01*
X640183Y37320D01*
X639763Y36615D01*
X639553Y35675D01*
X639133Y35126D01*
X638398Y34891D01*
X637663Y35048D01*
X637138Y35440D01*
X636823Y35988D01*
Y36536D01*
X637033Y37085D01*
X637558Y37555D01*
G01X641023Y41505D02*
Y43541D01*
G01X643123Y47335D02*
X636823D01*
Y50311D01*
G01X639868Y49215D02*
Y47335D01*
G01X636823Y54183D02*
Y56063D01*
G01Y55123D02*
X643123D01*
G01Y54183D02*
Y56063D01*
G01X636823Y61423D02*
X643123D01*
G01X636823Y59621D02*
Y63225D01*
G01X648399Y70782D02*
X648667Y71143D01*
X648897Y71350D01*
X649204Y71453D01*
X649472Y71350D01*
X649664Y71143D01*
X649817Y70833D01*
X649855Y70472D01*
X649817Y70162D01*
X649664Y69852D01*
X649434Y69593D01*
X649165Y69490D01*
X648859Y69593D01*
X648590Y69903D01*
X648437Y70368D01*
X648399Y70885D01*
X648475Y71557D01*
X648590Y71918D01*
X648782Y72280D01*
X649050Y72538D01*
X649319Y72590D01*
X649587Y72487D01*
X649779Y72228D01*
G01X651713Y111850D02*
Y97401D01*
X679075D01*
G01X662748Y78386D02*
Y86693D01*
X644126D01*
Y102944D01*
G01X662748Y78386D02*
X633870D01*
Y103444D01*
G01X651713Y129850D02*
Y111850D01*
G01X633870Y113744D02*
Y132244D01*
G01X644126Y114344D02*
Y128044D01*
G01X629573Y142600D02*
Y127600D01*
G01X706437Y134650D02*
Y144645D01*
X651713D01*
Y134650D01*
G01X644126Y136444D02*
Y162044D01*
G01X633870Y132244D02*
Y162544D01*
G01Y173144D02*
Y172844D01*
Y198386D01*
X799106D01*
Y172844D01*
G01X644126Y173344D02*
Y181850D01*
X713988D01*
Y86693D01*
G01X673512Y-333400D02*
X675912D01*
G01X674712D02*
Y-341400D01*
G01X673512D02*
X675912D01*
G01X681312D02*
Y-336067D01*
G01Y-337133D02*
X681812Y-336600D01*
X682312Y-336200D01*
X683012Y-336067D01*
X683512Y-336200D01*
X684112Y-336600D01*
G01X689212Y-337800D02*
X692412D01*
X692112Y-336867D01*
X691612Y-336333D01*
X690912Y-336067D01*
X690212Y-336200D01*
X689612Y-336600D01*
X689212Y-337533D01*
X689012Y-338334D01*
Y-339133D01*
X689212Y-339933D01*
X689712Y-340733D01*
X690312Y-341267D01*
X691012Y-341400D01*
X691712Y-341133D01*
X692412Y-340334D01*
G01X697012Y-341400D02*
Y-336067D01*
G01Y-337400D02*
X697412Y-336733D01*
X698012Y-336200D01*
X698812Y-336067D01*
X699512Y-336200D01*
X700112Y-336733D01*
X700412Y-337667D01*
Y-341400D01*
G01X705212Y-337800D02*
X708412D01*
X708112Y-336867D01*
X707612Y-336333D01*
X706912Y-336067D01*
X706212Y-336200D01*
X705612Y-336600D01*
X705212Y-337533D01*
X705012Y-338334D01*
Y-339133D01*
X705212Y-339933D01*
X705712Y-340733D01*
X706312Y-341267D01*
X707012Y-341400D01*
X707712Y-341133D01*
X708412Y-340334D01*
G01X662612Y-315334D02*
X663412Y-316000D01*
X664312Y-316400D01*
X665112D01*
X665912Y-316000D01*
X666512Y-315334D01*
X666812Y-314400D01*
X666612Y-313467D01*
X666112Y-312667D01*
X665212Y-312133D01*
X664012Y-311867D01*
X663312Y-311333D01*
X663012Y-310400D01*
X663212Y-309467D01*
X663712Y-308800D01*
X664412Y-308400D01*
X665112D01*
X665812Y-308667D01*
X666412Y-309333D01*
G01X671512Y-308400D02*
X673912D01*
G01X672712D02*
Y-316400D01*
G01X671512D02*
X673912D01*
G01X678712Y-308400D02*
Y-316400D01*
X682712D01*
G01X686512D02*
Y-308400D01*
G01X690312D02*
X686512Y-313334D01*
G01X690912Y-316400D02*
X688212Y-311067D01*
G01X695412Y-313733D02*
X698012D01*
G01X704712Y-308400D02*
Y-316400D01*
G01X702412Y-308400D02*
X707012D01*
G01X712712Y-316400D02*
X711912Y-316267D01*
X711212Y-315733D01*
X710612Y-314933D01*
X710212Y-314000D01*
X710012Y-312933D01*
Y-311867D01*
X710212Y-310800D01*
X710612Y-309867D01*
X711212Y-309067D01*
X711912Y-308533D01*
X712712Y-308400D01*
X713512Y-308533D01*
X714212Y-309067D01*
X714812Y-309867D01*
X715212Y-310800D01*
X715412Y-311867D01*
Y-312933D01*
X715212Y-314000D01*
X714812Y-314933D01*
X714212Y-315733D01*
X713512Y-316267D01*
X712712Y-316400D01*
G01X718712D02*
Y-308400D01*
X721112D01*
X721912Y-308800D01*
X722512Y-309733D01*
X722712Y-310800D01*
X722512Y-311867D01*
X722012Y-312667D01*
X721112Y-313067D01*
X718712D01*
G01X666487Y69790D02*
Y72890D01*
X665069Y70668D01*
X666985D01*
G01X655884Y70055D02*
X656114Y69797D01*
X656382Y69642D01*
X656727Y69590D01*
X657072Y69693D01*
X657340Y69900D01*
X657532Y70262D01*
X657570Y70675D01*
X657494Y71088D01*
X657302Y71347D01*
X657034Y71553D01*
X656765Y71605D01*
X656497Y71553D01*
X656152Y71347D01*
X656267Y72690D01*
X657302D01*
G01X671984Y70610D02*
X672214Y70248D01*
X672520Y70042D01*
X672865Y69990D01*
X673172Y70042D01*
X673479Y70300D01*
X673670Y70610D01*
X673709Y70920D01*
X673632Y71282D01*
X673364Y71540D01*
X673095Y71643D01*
X672750D01*
G01X673095D02*
X673325Y71798D01*
X673517Y72057D01*
X673594Y72367D01*
X673517Y72677D01*
X673325Y72935D01*
X672980Y73090D01*
X672635Y73038D01*
X672290Y72832D01*
G01X694369Y3699D02*
X695327Y6799D01*
X696285Y3699D01*
G01X695940Y4784D02*
X694714D01*
G01X696207Y20613D02*
X695977Y20768D01*
X695709Y20871D01*
X695402D01*
X695057Y20716D01*
X694789Y20458D01*
X694597Y20148D01*
X694444Y19631D01*
X694406Y19166D01*
X694482Y18701D01*
X694597Y18391D01*
X694827Y18081D01*
X695096Y17874D01*
X695364Y17771D01*
X695632D01*
X695901Y17874D01*
X696131Y18029D01*
X696322Y18236D01*
G01X695971Y14036D02*
X696124Y14191D01*
X696239Y14450D01*
X696316Y14811D01*
X696239Y15121D01*
X696086Y15328D01*
X695817Y15483D01*
X694782D01*
Y12383D01*
X696047D01*
X696316Y12590D01*
X696469Y12900D01*
X696546Y13261D01*
X696469Y13623D01*
X696239Y13933D01*
X695971Y14036D01*
X694782D01*
G01X696331Y29147D02*
X694797D01*
Y32247D01*
X696331D01*
G01X695717Y30749D02*
X694797D01*
G01X695021Y23159D02*
Y26259D01*
X695787D01*
X696094Y26104D01*
X696324Y25897D01*
X696516Y25587D01*
X696669Y25226D01*
X696707Y24709D01*
X696669Y24192D01*
X696516Y23831D01*
X696324Y23521D01*
X696094Y23314D01*
X695787Y23159D01*
X695021D01*
G01X694636Y34435D02*
Y37535D01*
X696092D01*
G01X695556Y36037D02*
X694636D01*
G01X695494Y41273D02*
X696261D01*
Y40343D01*
X696031Y40033D01*
X695762Y39826D01*
X695379Y39723D01*
X694996Y39826D01*
X694727Y40033D01*
X694497Y40343D01*
X694344Y40705D01*
X694267Y41118D01*
Y41480D01*
X694344Y41790D01*
X694497Y42151D01*
X694727Y42461D01*
X694957Y42668D01*
X695264Y42823D01*
X695532D01*
X695839Y42720D01*
X696069Y42513D01*
G01X695841Y48288D02*
Y45188D01*
G01X694231D02*
Y48288D01*
G01Y46738D02*
X695841D01*
G01X695496Y50700D02*
X694576D01*
G01X695036D02*
Y53800D01*
G01X695496D02*
X694576D01*
G01X680899Y72673D02*
X681129Y72983D01*
X681397Y73138D01*
X681704Y73190D01*
X682087Y73087D01*
X682355Y72828D01*
X682432Y72518D01*
X682394Y72208D01*
X682240Y71950D01*
X681474Y71433D01*
X681129Y71072D01*
X680899Y70555D01*
X680822Y70090D01*
X682432D01*
G01X689227Y70290D02*
Y73390D01*
X688767Y72770D01*
G01Y70290D02*
X689687D01*
G01X679075Y97401D02*
X706437D01*
Y111850D01*
G01X713988Y86693D02*
X697000D01*
Y78386D01*
G01X737590D02*
X697000D01*
G01X708381Y4240D02*
X708691Y4432D01*
X708898Y4662D01*
X709001Y4930D01*
X708898Y5237D01*
X708691Y5467D01*
X708381Y5697D01*
X707968Y5774D01*
X705901D01*
G01X706418Y7379D02*
X706108Y7609D01*
X705953Y7877D01*
X705901Y8184D01*
X706004Y8567D01*
X706263Y8835D01*
X706573Y8912D01*
X706883Y8874D01*
X707141Y8720D01*
X707658Y7954D01*
X708019Y7609D01*
X708536Y7379D01*
X709001Y7302D01*
Y8912D01*
G01X708536Y10364D02*
X708794Y10594D01*
X708949Y10862D01*
X709001Y11207D01*
X708898Y11552D01*
X708691Y11820D01*
X708329Y12012D01*
X707916Y12050D01*
X707503Y11974D01*
X707244Y11782D01*
X707038Y11514D01*
X706986Y11245D01*
X707038Y10977D01*
X707244Y10632D01*
X705901Y10747D01*
Y11782D01*
G01X710505Y10040D02*
X711132Y9515D01*
X711837Y9200D01*
X712463D01*
X713090Y9515D01*
X713560Y10040D01*
X713795Y10775D01*
X713638Y11510D01*
X713247Y12140D01*
X712542Y12560D01*
X711602Y12770D01*
X711053Y13190D01*
X710818Y13925D01*
X710975Y14660D01*
X711367Y15185D01*
X711915Y15500D01*
X712463D01*
X713012Y15290D01*
X713482Y14765D01*
G01X716492Y9200D02*
X718450Y15500D01*
X720408Y9200D01*
G01X719703Y11405D02*
X717197D01*
G01X723105Y10040D02*
X723732Y9515D01*
X724437Y9200D01*
X725063D01*
X725690Y9515D01*
X726160Y10040D01*
X726395Y10775D01*
X726238Y11510D01*
X725847Y12140D01*
X725142Y12560D01*
X724202Y12770D01*
X723653Y13190D01*
X723418Y13925D01*
X723575Y14660D01*
X723967Y15185D01*
X724515Y15500D01*
X725063D01*
X725612Y15290D01*
X726082Y14765D01*
G01X704992Y18700D02*
X706950Y25000D01*
X708908Y18700D01*
G01X708203Y20905D02*
X705697D01*
G01X712310Y25000D02*
X714190D01*
G01X713250D02*
Y18700D01*
G01X712310D02*
X714190D01*
G01X717983D02*
Y25000D01*
X719942D01*
X720568Y24685D01*
X720960Y24265D01*
X721117Y23425D01*
X720960Y22585D01*
X720490Y22060D01*
X719942Y21745D01*
X717983D01*
G01X719942D02*
X721117Y18700D01*
G01X723813D02*
Y25000D01*
X725850Y19750D01*
X727887Y25000D01*
Y18700D01*
G01X730192D02*
X732150Y25000D01*
X734108Y18700D01*
G01X733403Y20905D02*
X730897D01*
G01X736805Y18700D02*
X740095Y25000D01*
G01X736805D02*
X740095Y18700D01*
G01X711390Y49700D02*
Y56000D01*
X708492Y51485D01*
X712408D01*
G01X714400Y51800D02*
X715183Y53900D01*
X715967D01*
X717533Y49700D01*
X718317D01*
X719100Y51800D01*
G01X722893Y49700D02*
X723050Y51065D01*
X723285Y52220D01*
X723598Y53270D01*
X723990Y54425D01*
X724617Y56000D01*
X721483D01*
G01X706405Y63240D02*
X707032Y62715D01*
X707737Y62400D01*
X708363D01*
X708990Y62715D01*
X709460Y63240D01*
X709695Y63975D01*
X709538Y64710D01*
X709147Y65340D01*
X708442Y65760D01*
X707502Y65970D01*
X706953Y66390D01*
X706718Y67125D01*
X706875Y67860D01*
X707267Y68385D01*
X707815Y68700D01*
X708363D01*
X708912Y68490D01*
X709382Y67965D01*
G01X712392Y62400D02*
X714350Y68700D01*
X716308Y62400D01*
G01X715603Y64605D02*
X713097D01*
G01X719005Y63240D02*
X719632Y62715D01*
X720337Y62400D01*
X720963D01*
X721590Y62715D01*
X722060Y63240D01*
X722295Y63975D01*
X722138Y64710D01*
X721747Y65340D01*
X721042Y65760D01*
X720102Y65970D01*
X719553Y66390D01*
X719318Y67125D01*
X719475Y67860D01*
X719867Y68385D01*
X720415Y68700D01*
X720963D01*
X721512Y68490D01*
X721982Y67965D01*
G01X717802Y72151D02*
X717955Y72306D01*
X718070Y72565D01*
X718147Y72926D01*
X718070Y73236D01*
X717917Y73443D01*
X717648Y73598D01*
X716613D01*
Y70498D01*
X717878D01*
X718147Y70705D01*
X718300Y71015D01*
X718377Y71376D01*
X718300Y71738D01*
X718070Y72048D01*
X717802Y72151D01*
X716613D01*
G01X720595Y70498D02*
Y73598D01*
X720135Y72978D01*
G01Y70498D02*
X721055D01*
G01X716337Y74517D02*
X717295Y77617D01*
X718253Y74517D01*
G01X717908Y75602D02*
X716682D01*
G01X720395Y74517D02*
Y77617D01*
X719935Y76997D01*
G01Y74517D02*
X720855D01*
G01X706848Y77117D02*
Y74895D01*
X707001Y74430D01*
X707308Y74120D01*
X707691Y74017D01*
X708074Y74120D01*
X708381Y74430D01*
X708534Y74895D01*
Y77117D01*
G01X709948Y74637D02*
X710178Y74275D01*
X710484Y74069D01*
X710829Y74017D01*
X711136Y74069D01*
X711443Y74327D01*
X711634Y74637D01*
X711673Y74947D01*
X711596Y75309D01*
X711328Y75567D01*
X711059Y75670D01*
X710714D01*
G01X711059D02*
X711289Y75825D01*
X711481Y76084D01*
X711558Y76394D01*
X711481Y76704D01*
X711289Y76962D01*
X710944Y77117D01*
X710599Y77065D01*
X710254Y76859D01*
G01X737590Y86693D02*
X718988D01*
Y181850D01*
X788850D01*
Y173344D01*
G01X706437Y111850D02*
Y129750D01*
G01X716549Y100803D02*
X716394Y100956D01*
X716135Y101071D01*
X715774Y101148D01*
X715464Y101071D01*
X715257Y100918D01*
X715102Y100649D01*
Y99614D01*
X718202D01*
Y100879D01*
X717995Y101148D01*
X717685Y101301D01*
X717324Y101378D01*
X716962Y101301D01*
X716652Y101071D01*
X716549Y100803D01*
Y99614D01*
G01X718202Y103596D02*
X715102D01*
X715722Y103136D01*
G01X718202D02*
Y104056D01*
G01X717582Y105853D02*
X717944Y106083D01*
X718150Y106389D01*
X718202Y106734D01*
X718150Y107041D01*
X717892Y107348D01*
X717582Y107539D01*
X717272Y107578D01*
X716910Y107501D01*
X716652Y107233D01*
X716549Y106964D01*
Y106619D01*
G01Y106964D02*
X716394Y107194D01*
X716135Y107386D01*
X715825Y107463D01*
X715515Y107386D01*
X715257Y107194D01*
X715102Y106849D01*
X715154Y106504D01*
X715360Y106159D01*
G01X717983Y115338D02*
X714883Y116296D01*
X717983Y117254D01*
G01X716898Y116909D02*
Y115683D01*
G01X717983Y119396D02*
X714883D01*
X715503Y118936D01*
G01X717983D02*
Y119856D01*
G01X717363Y121653D02*
X717725Y121883D01*
X717931Y122189D01*
X717983Y122534D01*
X717931Y122841D01*
X717673Y123148D01*
X717363Y123339D01*
X717053Y123378D01*
X716691Y123301D01*
X716433Y123033D01*
X716330Y122764D01*
Y122419D01*
G01Y122764D02*
X716175Y122994D01*
X715916Y123186D01*
X715606Y123263D01*
X715296Y123186D01*
X715038Y122994D01*
X714883Y122649D01*
X714935Y122304D01*
X715141Y121959D01*
G01X764500Y61200D02*
Y16000D01*
X741700D01*
Y61200D01*
X764500D01*
G01X743843Y23628D02*
Y26728D01*
X744802D01*
X745108Y26573D01*
X745300Y26366D01*
X745377Y25953D01*
X745300Y25540D01*
X745070Y25281D01*
X744802Y25126D01*
X743843D01*
G01X744802D02*
X745377Y23628D01*
G01X746867Y24248D02*
X747097Y23886D01*
X747403Y23680D01*
X747748Y23628D01*
X748055Y23680D01*
X748362Y23938D01*
X748553Y24248D01*
X748592Y24558D01*
X748515Y24920D01*
X748247Y25178D01*
X747978Y25281D01*
X747633D01*
G01X747978D02*
X748208Y25436D01*
X748400Y25695D01*
X748477Y26005D01*
X748400Y26315D01*
X748208Y26573D01*
X747863Y26728D01*
X747518Y26676D01*
X747173Y26470D01*
G01X742943Y28510D02*
Y31610D01*
X743902D01*
X744208Y31455D01*
X744400Y31248D01*
X744477Y30835D01*
X744400Y30422D01*
X744170Y30163D01*
X743902Y30008D01*
X742943D01*
G01X743902D02*
X744477Y28510D01*
G01X746810D02*
Y31610D01*
X746350Y30990D01*
G01Y28510D02*
X747270D01*
G01X749910D02*
Y31610D01*
X749450Y30990D01*
G01Y28510D02*
X750370D01*
G01X743843Y18510D02*
Y21610D01*
X744802D01*
X745108Y21455D01*
X745300Y21248D01*
X745377Y20835D01*
X745300Y20422D01*
X745070Y20163D01*
X744802Y20008D01*
X743843D01*
G01X744802D02*
X745377Y18510D01*
G01X747710D02*
Y21610D01*
X747250Y20990D01*
G01Y18510D02*
X748170D01*
G01X744107Y51400D02*
Y54500D01*
X744873D01*
X745180Y54345D01*
X745410Y54138D01*
X745602Y53828D01*
X745755Y53467D01*
X745793Y52950D01*
X745755Y52433D01*
X745602Y52072D01*
X745410Y51762D01*
X745180Y51555D01*
X744873Y51400D01*
X744107D01*
G01X741900Y49200D02*
X747800D01*
Y61000D01*
G01X743043Y33110D02*
Y36210D01*
X744002D01*
X744308Y36055D01*
X744500Y35848D01*
X744577Y35435D01*
X744500Y35022D01*
X744270Y34763D01*
X744002Y34608D01*
X743043D01*
G01X744002D02*
X744577Y33110D01*
G01X746910D02*
Y36210D01*
X746450Y35590D01*
G01Y33110D02*
X747370D01*
G01X749167Y33575D02*
X749397Y33317D01*
X749665Y33162D01*
X750010Y33110D01*
X750355Y33213D01*
X750623Y33420D01*
X750815Y33782D01*
X750853Y34195D01*
X750777Y34608D01*
X750585Y34867D01*
X750317Y35073D01*
X750048Y35125D01*
X749780Y35073D01*
X749435Y34867D01*
X749550Y36210D01*
X750585D01*
G01X726555Y97401D02*
X753917D01*
G01X737590Y78386D02*
Y86693D01*
G01X726555Y129850D02*
Y111850D01*
G01X781279Y134650D02*
Y144645D01*
X726555D01*
Y134650D01*
G01X753671Y18124D02*
Y21224D01*
X754630D01*
X754936Y21069D01*
X755128Y20862D01*
X755205Y20449D01*
X755128Y20036D01*
X754898Y19777D01*
X754630Y19622D01*
X753671D01*
G01X754630D02*
X755205Y18124D01*
G01X757998D02*
Y21224D01*
X756580Y19002D01*
X758496D01*
G01X760638Y21224D02*
X760331Y21121D01*
X760101Y20862D01*
X759948Y20552D01*
X759833Y20139D01*
X759795Y19674D01*
X759833Y19209D01*
X759948Y18796D01*
X760101Y18486D01*
X760331Y18227D01*
X760638Y18124D01*
X760945Y18227D01*
X761175Y18486D01*
X761328Y18796D01*
X761443Y19209D01*
X761481Y19674D01*
X761443Y20139D01*
X761328Y20552D01*
X761175Y20862D01*
X760945Y21121D01*
X760638Y21224D01*
G01X753671Y23106D02*
Y26206D01*
X754630D01*
X754936Y26051D01*
X755128Y25844D01*
X755205Y25431D01*
X755128Y25018D01*
X754898Y24759D01*
X754630Y24604D01*
X753671D01*
G01X754630D02*
X755205Y23106D01*
G01X757998D02*
Y26206D01*
X756580Y23984D01*
X758496D01*
G01X760638Y23106D02*
Y26206D01*
X760178Y25586D01*
G01Y23106D02*
X761098D01*
G01X753671Y28124D02*
Y31224D01*
X754630D01*
X754936Y31069D01*
X755128Y30862D01*
X755205Y30449D01*
X755128Y30036D01*
X754898Y29777D01*
X754630Y29622D01*
X753671D01*
G01X754630D02*
X755205Y28124D01*
G01X757998D02*
Y31224D01*
X756580Y29002D01*
X758496D01*
G01X759910Y30707D02*
X760140Y31017D01*
X760408Y31172D01*
X760715Y31224D01*
X761098Y31121D01*
X761366Y30862D01*
X761443Y30552D01*
X761405Y30242D01*
X761251Y29984D01*
X760485Y29467D01*
X760140Y29106D01*
X759910Y28589D01*
X759833Y28124D01*
X761443D01*
G01X749633Y51921D02*
Y55021D01*
X751089D01*
G01X750553Y53523D02*
X749633D01*
G01X752656Y52334D02*
X752963Y52076D01*
X753308Y51921D01*
X753614D01*
X753921Y52076D01*
X754151Y52334D01*
X754266Y52696D01*
X754189Y53058D01*
X753998Y53368D01*
X753653Y53574D01*
X753193Y53678D01*
X752924Y53884D01*
X752809Y54246D01*
X752886Y54608D01*
X753078Y54866D01*
X753346Y55021D01*
X753614D01*
X753883Y54918D01*
X754113Y54659D01*
G01X755718Y52541D02*
X755948Y52179D01*
X756254Y51973D01*
X756599Y51921D01*
X756906Y51973D01*
X757213Y52231D01*
X757404Y52541D01*
X757443Y52851D01*
X757366Y53213D01*
X757098Y53471D01*
X756829Y53574D01*
X756484D01*
G01X756829D02*
X757059Y53729D01*
X757251Y53988D01*
X757328Y54298D01*
X757251Y54608D01*
X757059Y54866D01*
X756714Y55021D01*
X756369Y54969D01*
X756024Y54763D01*
G01X749197Y45583D02*
X752297D01*
Y47117D01*
G01X751677Y48607D02*
X752039Y48837D01*
X752245Y49143D01*
X752297Y49488D01*
X752245Y49795D01*
X751987Y50102D01*
X751677Y50293D01*
X751367Y50332D01*
X751005Y50255D01*
X750747Y49987D01*
X750644Y49718D01*
Y49373D01*
G01Y49718D02*
X750489Y49948D01*
X750230Y50140D01*
X749920Y50217D01*
X749610Y50140D01*
X749352Y49948D01*
X749197Y49603D01*
X749249Y49258D01*
X749455Y48913D01*
G01X753925Y45983D02*
X757025D01*
Y47517D01*
G01Y49850D02*
X753925D01*
X754545Y49390D01*
G01X757025D02*
Y50310D01*
G01X753671Y33124D02*
Y36224D01*
X754630D01*
X754936Y36069D01*
X755128Y35862D01*
X755205Y35449D01*
X755128Y35036D01*
X754898Y34777D01*
X754630Y34622D01*
X753671D01*
G01X754630D02*
X755205Y33124D01*
G01X757998D02*
Y36224D01*
X756580Y34002D01*
X758496D01*
G01X759795Y33744D02*
X760025Y33382D01*
X760331Y33176D01*
X760676Y33124D01*
X760983Y33176D01*
X761290Y33434D01*
X761481Y33744D01*
X761520Y34054D01*
X761443Y34416D01*
X761175Y34674D01*
X760906Y34777D01*
X760561D01*
G01X760906D02*
X761136Y34932D01*
X761328Y35191D01*
X761405Y35501D01*
X761328Y35811D01*
X761136Y36069D01*
X760791Y36224D01*
X760446Y36172D01*
X760101Y35966D01*
G01X748483Y41342D02*
Y44442D01*
X749442D01*
X749748Y44287D01*
X749940Y44080D01*
X750017Y43667D01*
X749940Y43254D01*
X749710Y42995D01*
X749442Y42840D01*
X748483D01*
G01X749442D02*
X750017Y41342D01*
G01X752273D02*
X752350Y42014D01*
X752465Y42582D01*
X752618Y43099D01*
X752810Y43667D01*
X753117Y44442D01*
X751583D01*
G01X755373Y41342D02*
X755450Y42014D01*
X755565Y42582D01*
X755718Y43099D01*
X755910Y43667D01*
X756217Y44442D01*
X754683D01*
G01X748383Y37242D02*
Y40342D01*
X749342D01*
X749648Y40187D01*
X749840Y39980D01*
X749917Y39567D01*
X749840Y39154D01*
X749610Y38895D01*
X749342Y38740D01*
X748383D01*
G01X749342D02*
X749917Y37242D01*
G01X752173D02*
X752250Y37914D01*
X752365Y38482D01*
X752518Y38999D01*
X752710Y39567D01*
X753017Y40342D01*
X751483D01*
G01X754622Y38534D02*
X754890Y38895D01*
X755120Y39102D01*
X755427Y39205D01*
X755695Y39102D01*
X755887Y38895D01*
X756040Y38585D01*
X756078Y38224D01*
X756040Y37914D01*
X755887Y37604D01*
X755657Y37345D01*
X755388Y37242D01*
X755082Y37345D01*
X754813Y37655D01*
X754660Y38120D01*
X754622Y38637D01*
X754698Y39309D01*
X754813Y39670D01*
X755005Y40032D01*
X755273Y40290D01*
X755542Y40342D01*
X755810Y40239D01*
X756002Y39980D01*
G01X749828Y56085D02*
Y59185D01*
X751284D01*
G01X750748Y57687D02*
X749828D01*
G01X752851Y56498D02*
X753158Y56240D01*
X753503Y56085D01*
X753809D01*
X754116Y56240D01*
X754346Y56498D01*
X754461Y56860D01*
X754384Y57222D01*
X754193Y57532D01*
X753848Y57738D01*
X753388Y57842D01*
X753119Y58048D01*
X753004Y58410D01*
X753081Y58772D01*
X753273Y59030D01*
X753541Y59185D01*
X753809D01*
X754078Y59082D01*
X754308Y58823D01*
G01X756756Y56085D02*
Y59185D01*
X756296Y58565D01*
G01Y56085D02*
X757216D01*
G01X753917Y97401D02*
X781279D01*
Y111850D01*
G01X777812Y-334733D02*
X778412Y-333933D01*
X779112Y-333533D01*
X779912Y-333400D01*
X780912Y-333667D01*
X781612Y-334333D01*
X781812Y-335133D01*
X781712Y-335934D01*
X781312Y-336600D01*
X779312Y-337933D01*
X778412Y-338867D01*
X777812Y-340200D01*
X777612Y-341400D01*
X781812D01*
G01X787712Y-333400D02*
X786912Y-333667D01*
X786312Y-334333D01*
X785912Y-335133D01*
X785612Y-336200D01*
X785512Y-337400D01*
X785612Y-338600D01*
X785912Y-339667D01*
X786312Y-340467D01*
X786912Y-341133D01*
X787712Y-341400D01*
X788512Y-341133D01*
X789112Y-340467D01*
X789512Y-339667D01*
X789812Y-338600D01*
X789912Y-337400D01*
X789812Y-336200D01*
X789512Y-335133D01*
X789112Y-334333D01*
X788512Y-333667D01*
X787712Y-333400D01*
G01X795712Y-341400D02*
Y-333400D01*
X794512Y-335000D01*
G01Y-341400D02*
X796912D01*
G01X801812Y-334733D02*
X802412Y-333933D01*
X803112Y-333533D01*
X803912Y-333400D01*
X804912Y-333667D01*
X805612Y-334333D01*
X805812Y-335133D01*
X805712Y-335934D01*
X805312Y-336600D01*
X803312Y-337933D01*
X802412Y-338867D01*
X801812Y-340200D01*
X801612Y-341400D01*
X805812D01*
G01X809912Y-341667D02*
X813512Y-333400D01*
G01X819712Y-341400D02*
Y-333400D01*
X818512Y-335000D01*
G01Y-341400D02*
X820912D01*
G01X827712Y-333400D02*
X826912Y-333667D01*
X826312Y-334333D01*
X825912Y-335133D01*
X825612Y-336200D01*
X825512Y-337400D01*
X825612Y-338600D01*
X825912Y-339667D01*
X826312Y-340467D01*
X826912Y-341133D01*
X827712Y-341400D01*
X828512Y-341133D01*
X829112Y-340467D01*
X829512Y-339667D01*
X829812Y-338600D01*
X829912Y-337400D01*
X829812Y-336200D01*
X829512Y-335133D01*
X829112Y-334333D01*
X828512Y-333667D01*
X827712Y-333400D01*
G01X833912Y-341667D02*
X837512Y-333400D01*
G01X841512Y-339800D02*
X842112Y-340733D01*
X842912Y-341267D01*
X843812Y-341400D01*
X844612Y-341267D01*
X845412Y-340600D01*
X845912Y-339800D01*
X846012Y-339000D01*
X845812Y-338067D01*
X845112Y-337400D01*
X844412Y-337133D01*
X843512D01*
G01X844412D02*
X845012Y-336733D01*
X845512Y-336067D01*
X845712Y-335267D01*
X845512Y-334467D01*
X845012Y-333800D01*
X844112Y-333400D01*
X843212Y-333533D01*
X842312Y-334067D01*
G01X851712Y-341400D02*
Y-333400D01*
X850512Y-335000D01*
G01Y-341400D02*
X852912D01*
G01X777512Y-316400D02*
Y-308400D01*
X779512D01*
X780312Y-308800D01*
X780912Y-309333D01*
X781412Y-310133D01*
X781812Y-311067D01*
X781912Y-312400D01*
X781812Y-313733D01*
X781412Y-314667D01*
X780912Y-315467D01*
X780312Y-316000D01*
X779512Y-316400D01*
X777512D01*
G01X785212D02*
X787712Y-308400D01*
X790212Y-316400D01*
G01X789312Y-313600D02*
X786112D01*
G01X795712Y-308400D02*
X794912Y-308667D01*
X794312Y-309333D01*
X793912Y-310133D01*
X793612Y-311200D01*
X793512Y-312400D01*
X793612Y-313600D01*
X793912Y-314667D01*
X794312Y-315467D01*
X794912Y-316133D01*
X795712Y-316400D01*
X796512Y-316133D01*
X797112Y-315467D01*
X797512Y-314667D01*
X797812Y-313600D01*
X797912Y-312400D01*
X797812Y-311200D01*
X797512Y-310133D01*
X797112Y-309333D01*
X796512Y-308667D01*
X795712Y-308400D01*
G01X803712D02*
Y-316400D01*
G01X801412Y-308400D02*
X806012D01*
G01X809812Y-313067D02*
X810512Y-312133D01*
X811112Y-311600D01*
X811912Y-311333D01*
X812612Y-311600D01*
X813112Y-312133D01*
X813512Y-312933D01*
X813612Y-313867D01*
X813512Y-314667D01*
X813112Y-315467D01*
X812512Y-316133D01*
X811812Y-316400D01*
X811012Y-316133D01*
X810312Y-315334D01*
X809912Y-314133D01*
X809812Y-312800D01*
X810012Y-311067D01*
X810312Y-310133D01*
X810812Y-309200D01*
X811512Y-308533D01*
X812212Y-308400D01*
X812912Y-308667D01*
X813412Y-309333D01*
G01X817112Y-316400D02*
Y-308400D01*
X819712Y-315067D01*
X822312Y-308400D01*
Y-316400D01*
G01X827712Y-308400D02*
Y-316400D01*
G01X825412Y-308400D02*
X830012D01*
G01X833612Y-316400D02*
Y-308400D01*
G01X837812D02*
Y-316400D01*
G01Y-312400D02*
X833612D01*
G01X843712Y-316400D02*
X844412Y-316267D01*
X845212Y-315867D01*
X845712Y-315200D01*
X845912Y-314267D01*
X845712Y-313334D01*
X845112Y-312533D01*
X844212Y-312133D01*
X843212D01*
X842612Y-311867D01*
X842112Y-311200D01*
X841912Y-310267D01*
X842212Y-309333D01*
X842912Y-308667D01*
X843712Y-308400D01*
X844512Y-308667D01*
X845212Y-309333D01*
X845512Y-310267D01*
X845312Y-311200D01*
X844812Y-311867D01*
X844212Y-312133D01*
X843212D01*
X842312Y-312533D01*
X841712Y-313334D01*
X841512Y-314267D01*
X841712Y-315200D01*
X842212Y-315867D01*
X843012Y-316267D01*
X843712Y-316400D01*
G01X853912Y-309067D02*
X853312Y-308667D01*
X852612Y-308400D01*
X851812D01*
X850912Y-308800D01*
X850212Y-309467D01*
X849712Y-310267D01*
X849312Y-311600D01*
X849212Y-312800D01*
X849412Y-314000D01*
X849712Y-314800D01*
X850312Y-315600D01*
X851012Y-316133D01*
X851712Y-316400D01*
X852412D01*
X853112Y-316133D01*
X853712Y-315733D01*
X854212Y-315200D01*
G01X859712Y-308400D02*
X858912Y-308667D01*
X858312Y-309333D01*
X857912Y-310133D01*
X857612Y-311200D01*
X857512Y-312400D01*
X857612Y-313600D01*
X857912Y-314667D01*
X858312Y-315467D01*
X858912Y-316133D01*
X859712Y-316400D01*
X860512Y-316133D01*
X861112Y-315467D01*
X861512Y-314667D01*
X861812Y-313600D01*
X861912Y-312400D01*
X861812Y-311200D01*
X861512Y-310133D01*
X861112Y-309333D01*
X860512Y-308667D01*
X859712Y-308400D01*
G01X769605Y69740D02*
X770232Y69215D01*
X770937Y68900D01*
X771563D01*
X772190Y69215D01*
X772660Y69740D01*
X772895Y70475D01*
X772738Y71210D01*
X772347Y71840D01*
X771642Y72260D01*
X770702Y72470D01*
X770153Y72890D01*
X769918Y73625D01*
X770075Y74360D01*
X770467Y74885D01*
X771015Y75200D01*
X771563D01*
X772112Y74990D01*
X772582Y74465D01*
G01X775592Y68900D02*
X777550Y75200D01*
X779508Y68900D01*
G01X778803Y71105D02*
X776297D01*
G01X782205Y69740D02*
X782832Y69215D01*
X783537Y68900D01*
X784163D01*
X784790Y69215D01*
X785260Y69740D01*
X785495Y70475D01*
X785338Y71210D01*
X784947Y71840D01*
X784242Y72260D01*
X783302Y72470D01*
X782753Y72890D01*
X782518Y73625D01*
X782675Y74360D01*
X783067Y74885D01*
X783615Y75200D01*
X784163D01*
X784712Y74990D01*
X785182Y74465D01*
G01X771250Y65600D02*
X770623Y65390D01*
X770153Y64865D01*
X769840Y64235D01*
X769605Y63395D01*
X769527Y62450D01*
X769605Y61505D01*
X769840Y60665D01*
X770153Y60035D01*
X770623Y59510D01*
X771250Y59300D01*
X771877Y59510D01*
X772347Y60035D01*
X772660Y60665D01*
X772895Y61505D01*
X772973Y62450D01*
X772895Y63395D01*
X772660Y64235D01*
X772347Y64865D01*
X771877Y65390D01*
X771250Y65600D01*
G01X775200Y61400D02*
X775983Y63500D01*
X776767D01*
X778333Y59300D01*
X779117D01*
X779900Y61400D01*
G01X782127Y60560D02*
X782597Y59825D01*
X783223Y59405D01*
X783928Y59300D01*
X784555Y59405D01*
X785182Y59930D01*
X785573Y60560D01*
X785652Y61190D01*
X785495Y61925D01*
X784947Y62450D01*
X784398Y62660D01*
X783693D01*
G01X784398D02*
X784868Y62975D01*
X785260Y63500D01*
X785417Y64130D01*
X785260Y64760D01*
X784868Y65285D01*
X784163Y65600D01*
X783458Y65495D01*
X782753Y65075D01*
G01X788850Y102944D02*
Y86693D01*
X771842D01*
Y78386D01*
G01X799106Y103444D02*
Y78386D01*
X771842D01*
G01X781279Y111850D02*
Y129750D01*
G01X788850Y128044D02*
Y114344D01*
G01Y161944D02*
Y136544D01*
G01X799712Y-283400D02*
Y-291400D01*
G01X797412Y-283400D02*
X802012D01*
G01X805812Y-288067D02*
X806512Y-287133D01*
X807112Y-286600D01*
X807912Y-286333D01*
X808612Y-286600D01*
X809112Y-287133D01*
X809512Y-287933D01*
X809612Y-288867D01*
X809512Y-289667D01*
X809112Y-290467D01*
X808512Y-291133D01*
X807812Y-291400D01*
X807012Y-291133D01*
X806312Y-290334D01*
X805912Y-289133D01*
X805812Y-287800D01*
X806012Y-286067D01*
X806312Y-285133D01*
X806812Y-284200D01*
X807512Y-283533D01*
X808212Y-283400D01*
X808912Y-283667D01*
X809412Y-284333D01*
G01X813112Y-291400D02*
Y-283400D01*
X815712Y-290067D01*
X818312Y-283400D01*
Y-291400D01*
G01X820712Y-294067D02*
X826712D01*
G01X831712Y-283400D02*
Y-291400D01*
G01X829412Y-283400D02*
X834012D01*
G01X838312Y-291400D02*
Y-286067D01*
G01Y-287133D02*
X838812Y-286600D01*
X839312Y-286200D01*
X840012Y-286067D01*
X840512Y-286200D01*
X841112Y-286600D01*
G01X849512Y-291400D02*
Y-286067D01*
G01Y-287000D02*
X849112Y-286467D01*
X848512Y-286200D01*
X847812Y-286067D01*
X847112Y-286333D01*
X846512Y-286867D01*
X846112Y-287667D01*
X845912Y-288733D01*
X846112Y-289800D01*
X846512Y-290600D01*
X847112Y-291133D01*
X847812Y-291400D01*
X848512Y-291267D01*
X849112Y-290867D01*
X849512Y-290334D01*
G01X853612Y-293800D02*
X854212Y-294067D01*
X855012Y-293800D01*
X855512Y-293267D01*
X855912Y-292600D01*
X856512Y-290467D01*
X857812Y-286067D01*
G01X854612D02*
X856512Y-290467D01*
G01X860712Y-294067D02*
X866712D01*
G01X872512Y-287133D02*
X872912Y-286733D01*
X873212Y-286067D01*
X873412Y-285133D01*
X873212Y-284333D01*
X872812Y-283800D01*
X872112Y-283400D01*
X869412D01*
Y-291400D01*
X872712D01*
X873412Y-290867D01*
X873812Y-290067D01*
X874012Y-289133D01*
X873812Y-288200D01*
X873212Y-287400D01*
X872512Y-287133D01*
X869412D01*
G01X877712Y-291400D02*
Y-283400D01*
X880112D01*
X880912Y-283800D01*
X881512Y-284733D01*
X881712Y-285800D01*
X881512Y-286867D01*
X881012Y-287667D01*
X880112Y-288067D01*
X877712D01*
G01X790874Y76817D02*
Y74595D01*
X791027Y74130D01*
X791334Y73820D01*
X791717Y73717D01*
X792100Y73820D01*
X792407Y74130D01*
X792560Y74595D01*
Y76817D01*
G01X794817Y73717D02*
Y76817D01*
X794357Y76197D01*
G01Y73717D02*
X795277D01*
G01X791484Y60263D02*
Y63363D01*
G01X793094D02*
Y60263D01*
G01Y61813D02*
X791484D01*
G01X795389Y60263D02*
Y63363D01*
X794929Y62743D01*
G01Y60263D02*
X795849D01*
G01X802044Y98851D02*
X802197Y99006D01*
X802312Y99265D01*
X802389Y99626D01*
X802312Y99936D01*
X802159Y100143D01*
X801890Y100298D01*
X800855D01*
Y97198D01*
X802120D01*
X802389Y97405D01*
X802542Y97715D01*
X802619Y98076D01*
X802542Y98438D01*
X802312Y98748D01*
X802044Y98851D01*
X800855D01*
G01X804837Y97198D02*
Y100298D01*
X804377Y99678D01*
G01Y97198D02*
X805297D01*
G01X800779Y116117D02*
X801737Y119217D01*
X802695Y116117D01*
G01X802350Y117202D02*
X801124D01*
G01X804837Y116117D02*
Y119217D01*
X804377Y118597D01*
G01Y116117D02*
X805297D01*
G01X803168Y109138D02*
X803935D01*
Y108208D01*
X803705Y107898D01*
X803436Y107691D01*
X803053Y107588D01*
X802670Y107691D01*
X802401Y107898D01*
X802171Y108208D01*
X802018Y108570D01*
X801941Y108983D01*
Y109345D01*
X802018Y109655D01*
X802171Y110016D01*
X802401Y110326D01*
X802631Y110533D01*
X802938Y110688D01*
X803206D01*
X803513Y110585D01*
X803743Y110378D01*
G01X805310Y108880D02*
X805578Y109241D01*
X805808Y109448D01*
X806115Y109551D01*
X806383Y109448D01*
X806575Y109241D01*
X806728Y108931D01*
X806766Y108570D01*
X806728Y108260D01*
X806575Y107950D01*
X806345Y107691D01*
X806076Y107588D01*
X805770Y107691D01*
X805501Y108001D01*
X805348Y108466D01*
X805310Y108983D01*
X805386Y109655D01*
X805501Y110016D01*
X805693Y110378D01*
X805961Y110636D01*
X806230Y110688D01*
X806498Y110585D01*
X806690Y110326D01*
G01X799106Y162544D02*
Y113744D01*
G01X801468Y132761D02*
X802235D01*
Y131831D01*
X802005Y131521D01*
X801736Y131314D01*
X801353Y131211D01*
X800970Y131314D01*
X800701Y131521D01*
X800471Y131831D01*
X800318Y132193D01*
X800241Y132606D01*
Y132968D01*
X800318Y133278D01*
X800471Y133639D01*
X800701Y133949D01*
X800931Y134156D01*
X801238Y134311D01*
X801506D01*
X801813Y134208D01*
X802043Y134001D01*
G01X803495Y131676D02*
X803725Y131418D01*
X803993Y131263D01*
X804338Y131211D01*
X804683Y131314D01*
X804951Y131521D01*
X805143Y131883D01*
X805181Y132296D01*
X805105Y132709D01*
X804913Y132968D01*
X804645Y133174D01*
X804376Y133226D01*
X804108Y133174D01*
X803763Y132968D01*
X803878Y134311D01*
X804913D01*
G01X803468Y168194D02*
X804235D01*
Y167264D01*
X804005Y166954D01*
X803736Y166747D01*
X803353Y166644D01*
X802970Y166747D01*
X802701Y166954D01*
X802471Y167264D01*
X802318Y167626D01*
X802241Y168039D01*
Y168401D01*
X802318Y168711D01*
X802471Y169072D01*
X802701Y169382D01*
X802931Y169589D01*
X803238Y169744D01*
X803506D01*
X803813Y169641D01*
X804043Y169434D01*
G01X806798Y166644D02*
Y169744D01*
X805380Y167522D01*
X807296D01*
G01X824545Y14700D02*
Y22200D01*
X826785D01*
X827532Y21825D01*
X828092Y20950D01*
X828279Y19950D01*
X828092Y18950D01*
X827625Y18200D01*
X826785Y17825D01*
X824545D01*
G01X832232Y14450D02*
X835592Y22200D01*
G01X839265Y14700D02*
Y22200D01*
X843559Y14700D01*
Y22200D01*
G01X848912Y14450D02*
X848725Y14575D01*
Y14825D01*
X848912Y14950D01*
X849099Y14825D01*
Y14575D01*
X848912Y14450D01*
G01Y17825D02*
X848725Y17950D01*
Y18200D01*
X848912Y18325D01*
X849099Y18200D01*
Y17950D01*
X848912Y17825D01*
G01X854359Y14700D02*
Y22200D01*
X856225D01*
X856972Y21825D01*
X857532Y21325D01*
X857999Y20575D01*
X858372Y19700D01*
X858465Y18450D01*
X858372Y17200D01*
X857999Y16325D01*
X857532Y15575D01*
X856972Y15075D01*
X856225Y14700D01*
X854359D01*
G01X861579D02*
X863912Y22200D01*
X866245Y14700D01*
G01X865405Y17325D02*
X862419D01*
G01X871412Y22200D02*
X870665Y21950D01*
X870105Y21325D01*
X869732Y20575D01*
X869452Y19575D01*
X869359Y18450D01*
X869452Y17325D01*
X869732Y16325D01*
X870105Y15575D01*
X870665Y14950D01*
X871412Y14700D01*
X872159Y14950D01*
X872719Y15575D01*
X873092Y16325D01*
X873372Y17325D01*
X873465Y18450D01*
X873372Y19575D01*
X873092Y20575D01*
X872719Y21325D01*
X872159Y21950D01*
X871412Y22200D01*
G01X878912D02*
Y14700D01*
G01X876765Y22200D02*
X881059D01*
G01X884639Y17825D02*
X885292Y18700D01*
X885852Y19200D01*
X886599Y19450D01*
X887252Y19200D01*
X887719Y18700D01*
X888092Y17950D01*
X888185Y17075D01*
X888092Y16325D01*
X887719Y15575D01*
X887159Y14950D01*
X886505Y14700D01*
X885759Y14950D01*
X885105Y15700D01*
X884732Y16825D01*
X884639Y18075D01*
X884825Y19700D01*
X885105Y20575D01*
X885572Y21450D01*
X886225Y22075D01*
X886879Y22200D01*
X887532Y21950D01*
X887999Y21325D01*
G01X891485Y14700D02*
Y22200D01*
X893912Y15950D01*
X896339Y22200D01*
Y14700D01*
G01X901412Y22200D02*
Y14700D01*
G01X899265Y22200D02*
X903559D01*
G01X906952Y14700D02*
Y22200D01*
G01X910872D02*
Y14700D01*
G01Y18450D02*
X906952D01*
G01X916412Y14700D02*
X917065Y14825D01*
X917812Y15200D01*
X918279Y15825D01*
X918465Y16700D01*
X918279Y17575D01*
X917719Y18325D01*
X916879Y18700D01*
X915945D01*
X915385Y18950D01*
X914919Y19575D01*
X914732Y20450D01*
X915012Y21325D01*
X915665Y21950D01*
X916412Y22200D01*
X917159Y21950D01*
X917812Y21325D01*
X918092Y20450D01*
X917905Y19575D01*
X917439Y18950D01*
X916879Y18700D01*
X915945D01*
X915105Y18325D01*
X914545Y17575D01*
X914359Y16700D01*
X914545Y15825D01*
X915012Y15200D01*
X915759Y14825D01*
X916412Y14700D01*
G01X925965Y21575D02*
X925405Y21950D01*
X924752Y22200D01*
X924005D01*
X923165Y21825D01*
X922512Y21200D01*
X922045Y20450D01*
X921672Y19200D01*
X921579Y18075D01*
X921765Y16950D01*
X922045Y16200D01*
X922605Y15450D01*
X923259Y14950D01*
X923912Y14700D01*
X924565D01*
X925219Y14950D01*
X925779Y15325D01*
X926245Y15825D01*
G01X931412Y22200D02*
X930665Y21950D01*
X930105Y21325D01*
X929732Y20575D01*
X929452Y19575D01*
X929359Y18450D01*
X929452Y17325D01*
X929732Y16325D01*
X930105Y15575D01*
X930665Y14950D01*
X931412Y14700D01*
X932159Y14950D01*
X932719Y15575D01*
X933092Y16325D01*
X933372Y17325D01*
X933465Y18450D01*
X933372Y19575D01*
X933092Y20575D01*
X932719Y21325D01*
X932159Y21950D01*
X931412Y22200D01*
G01X831487Y53611D02*
X1028337D01*
Y29989D01*
X831487D01*
Y53611D01*
G01X853800Y4000D02*
Y12000D01*
X856300D01*
X857100Y11600D01*
X857600Y11067D01*
X857800Y10000D01*
X857600Y8933D01*
X857000Y8267D01*
X856300Y7867D01*
X853800D01*
G01X856300D02*
X857800Y4000D01*
G01X862300Y7600D02*
X865500D01*
X865200Y8533D01*
X864700Y9067D01*
X864000Y9333D01*
X863300Y9200D01*
X862700Y8800D01*
X862300Y7867D01*
X862100Y7066D01*
Y6267D01*
X862300Y5467D01*
X862800Y4667D01*
X863400Y4133D01*
X864100Y4000D01*
X864800Y4267D01*
X865500Y5066D01*
G01X870000Y9333D02*
X871800Y4000D01*
X873600Y9333D01*
G01X879800Y3733D02*
X879600Y3867D01*
Y4133D01*
X879800Y4267D01*
X880000Y4133D01*
Y3867D01*
X879800Y3733D01*
G01Y7333D02*
X879600Y7467D01*
Y7733D01*
X879800Y7867D01*
X880000Y7733D01*
Y7467D01*
X879800Y7333D01*
G01X890000Y11333D02*
X889400Y11733D01*
X888700Y12000D01*
X887900D01*
X887000Y11600D01*
X886300Y10933D01*
X885800Y10133D01*
X885400Y8800D01*
X885300Y7600D01*
X885500Y6400D01*
X885800Y5600D01*
X886400Y4800D01*
X887100Y4267D01*
X887800Y4000D01*
X888500D01*
X889200Y4267D01*
X889800Y4667D01*
X890300Y5200D01*
G01X840521Y146881D02*
Y149981D01*
G01X842131D02*
Y146881D01*
G01Y148431D02*
X840521D01*
G01X844886Y146881D02*
Y149981D01*
X843468Y147759D01*
X845384D01*
G01X877772Y40983D02*
X878552Y41763D01*
X879137Y43063D01*
X879527Y44883D01*
X879137Y46443D01*
X878357Y47483D01*
X876992Y48263D01*
X871727D01*
Y32663D01*
X878162D01*
X879527Y33703D01*
X880307Y35263D01*
X880697Y37083D01*
X880307Y38903D01*
X879137Y40463D01*
X877772Y40983D01*
X871727D01*
G01X897622Y32663D02*
Y43063D01*
G01Y41243D02*
X896842Y42283D01*
X895672Y42803D01*
X894307Y43063D01*
X892942Y42543D01*
X891772Y41503D01*
X890992Y39943D01*
X890602Y37863D01*
X890992Y35783D01*
X891772Y34223D01*
X892942Y33183D01*
X894307Y32663D01*
X895672Y32923D01*
X896842Y33703D01*
X897622Y34743D01*
G01X909282Y32663D02*
Y43063D01*
G01Y40983D02*
X910257Y42023D01*
X911232Y42803D01*
X912597Y43063D01*
X913572Y42803D01*
X914742Y42023D01*
G01X933032Y41763D02*
X931667Y42803D01*
X930497Y43063D01*
X928937Y42543D01*
X927767Y41503D01*
X926987Y39683D01*
X926792Y37863D01*
X926987Y36043D01*
X927767Y34483D01*
X928937Y33183D01*
X930497Y32663D01*
X931862Y33183D01*
X933032Y34223D01*
G01X947812Y32663D02*
X946642Y32923D01*
X945472Y33963D01*
X944692Y35783D01*
X944302Y37863D01*
X944692Y39943D01*
X945472Y41763D01*
X946642Y42803D01*
X947812Y43063D01*
X948982Y42803D01*
X950152Y41763D01*
X950932Y39943D01*
X951127Y37863D01*
X950932Y35783D01*
X950152Y33963D01*
X948982Y32923D01*
X947812Y32663D01*
G01X969222Y48263D02*
Y32663D01*
G01Y35003D02*
X968442Y33703D01*
X967272Y32923D01*
X965907Y32663D01*
X964347Y33183D01*
X963177Y34483D01*
X962397Y36043D01*
X962202Y37863D01*
X962397Y39683D01*
X963177Y41243D01*
X964347Y42543D01*
X965907Y43063D01*
X967272Y42803D01*
X968247Y42283D01*
X969222Y41243D01*
G01X980687Y39683D02*
X986927D01*
X986342Y41503D01*
X985367Y42543D01*
X984002Y43063D01*
X982637Y42803D01*
X981467Y42023D01*
X980687Y40203D01*
X980297Y38643D01*
Y37083D01*
X980687Y35523D01*
X981662Y33963D01*
X982832Y32923D01*
X984197Y32663D01*
X985562Y33183D01*
X986927Y34743D01*
G01X896912Y-334067D02*
X896312Y-333667D01*
X895612Y-333400D01*
X894812D01*
X893912Y-333800D01*
X893212Y-334467D01*
X892712Y-335267D01*
X892312Y-336600D01*
X892212Y-337800D01*
X892412Y-339000D01*
X892712Y-339800D01*
X893312Y-340600D01*
X894012Y-341133D01*
X894712Y-341400D01*
X895412D01*
X896112Y-341133D01*
X896712Y-340733D01*
X897212Y-340200D01*
G01X922212Y-341400D02*
Y-333400D01*
X921012Y-335000D01*
G01Y-341400D02*
X923412D01*
G01X928312Y-338067D02*
X929012Y-337133D01*
X929612Y-336600D01*
X930412Y-336333D01*
X931112Y-336600D01*
X931612Y-337133D01*
X932012Y-337933D01*
X932112Y-338867D01*
X932012Y-339667D01*
X931612Y-340467D01*
X931012Y-341133D01*
X930312Y-341400D01*
X929512Y-341133D01*
X928812Y-340334D01*
X928412Y-339133D01*
X928312Y-337800D01*
X928512Y-336067D01*
X928812Y-335133D01*
X929312Y-334200D01*
X930012Y-333533D01*
X930712Y-333400D01*
X931412Y-333667D01*
X931912Y-334333D01*
G01X1101030Y62763D02*
Y65863D01*
G01X1102640D02*
Y62763D01*
G01Y64313D02*
X1101030D01*
G01X1104207Y65346D02*
X1104437Y65656D01*
X1104705Y65811D01*
X1105012Y65863D01*
X1105395Y65760D01*
X1105663Y65501D01*
X1105740Y65191D01*
X1105702Y64881D01*
X1105548Y64623D01*
X1104782Y64106D01*
X1104437Y63745D01*
X1104207Y63228D01*
X1104130Y62763D01*
X1105740D01*
G01X1097883Y88500D02*
Y94800D01*
X1099763D01*
X1100390Y94485D01*
X1100860Y93750D01*
X1101017Y92910D01*
X1100860Y92070D01*
X1100468Y91440D01*
X1099763Y91125D01*
X1097883D01*
G01X1105750Y88500D02*
X1105123Y88605D01*
X1104575Y89025D01*
X1104105Y89655D01*
X1103792Y90390D01*
X1103635Y91230D01*
Y92070D01*
X1103792Y92910D01*
X1104105Y93645D01*
X1104575Y94275D01*
X1105123Y94695D01*
X1105750Y94800D01*
X1106377Y94695D01*
X1106925Y94275D01*
X1107395Y93645D01*
X1107708Y92910D01*
X1107865Y92070D01*
Y91230D01*
X1107708Y90390D01*
X1107395Y89655D01*
X1106925Y89025D01*
X1106377Y88605D01*
X1105750Y88500D01*
G01X1109700Y94800D02*
X1110797Y88500D01*
X1112050Y94800D01*
X1113303Y88500D01*
X1114400Y94800D01*
G01X1119917Y88500D02*
X1116783D01*
Y94800D01*
X1119917D01*
G01X1118663Y91755D02*
X1116783D01*
G01X1123083Y88500D02*
Y94800D01*
X1125042D01*
X1125668Y94485D01*
X1126060Y94065D01*
X1126217Y93225D01*
X1126060Y92385D01*
X1125590Y91860D01*
X1125042Y91545D01*
X1123083D01*
G01X1125042D02*
X1126217Y88500D01*
G01X1138973Y94275D02*
X1138503Y94590D01*
X1137955Y94800D01*
X1137328D01*
X1136623Y94485D01*
X1136075Y93960D01*
X1135683Y93330D01*
X1135370Y92280D01*
X1135292Y91335D01*
X1135448Y90390D01*
X1135683Y89760D01*
X1136153Y89130D01*
X1136702Y88710D01*
X1137250Y88500D01*
X1137798D01*
X1138347Y88710D01*
X1138817Y89025D01*
X1139208Y89445D01*
G01X1143550Y88500D02*
X1142923Y88605D01*
X1142375Y89025D01*
X1141905Y89655D01*
X1141592Y90390D01*
X1141435Y91230D01*
Y92070D01*
X1141592Y92910D01*
X1141905Y93645D01*
X1142375Y94275D01*
X1142923Y94695D01*
X1143550Y94800D01*
X1144177Y94695D01*
X1144725Y94275D01*
X1145195Y93645D01*
X1145508Y92910D01*
X1145665Y92070D01*
Y91230D01*
X1145508Y90390D01*
X1145195Y89655D01*
X1144725Y89025D01*
X1144177Y88605D01*
X1143550Y88500D01*
G01X1148048D02*
Y94800D01*
X1151652Y88500D01*
Y94800D01*
G01X1154348Y88500D02*
Y94800D01*
X1157952Y88500D01*
Y94800D01*
G01X1155800Y124500D02*
X1100400D01*
Y97000D01*
X1160100D01*
Y124500D01*
X1155800D01*
G01X1111471Y99009D02*
Y102109D01*
X1112430D01*
X1112736Y101954D01*
X1112928Y101747D01*
X1113005Y101334D01*
X1112928Y100921D01*
X1112698Y100662D01*
X1112430Y100507D01*
X1111471D01*
G01X1112430D02*
X1113005Y99009D01*
G01X1115261D02*
X1115338Y99681D01*
X1115453Y100249D01*
X1115606Y100766D01*
X1115798Y101334D01*
X1116105Y102109D01*
X1114571D01*
G01X1117595Y99629D02*
X1117825Y99267D01*
X1118131Y99061D01*
X1118476Y99009D01*
X1118783Y99061D01*
X1119090Y99319D01*
X1119281Y99629D01*
X1119320Y99939D01*
X1119243Y100301D01*
X1118975Y100559D01*
X1118706Y100662D01*
X1118361D01*
G01X1118706D02*
X1118936Y100817D01*
X1119128Y101076D01*
X1119205Y101386D01*
X1119128Y101696D01*
X1118936Y101954D01*
X1118591Y102109D01*
X1118246Y102057D01*
X1117901Y101851D01*
G01X1101895Y102506D02*
Y105606D01*
X1102854D01*
X1103160Y105451D01*
X1103352Y105244D01*
X1103429Y104831D01*
X1103352Y104418D01*
X1103122Y104159D01*
X1102854Y104004D01*
X1101895D01*
G01X1102854D02*
X1103429Y102506D01*
G01X1105034Y105089D02*
X1105264Y105399D01*
X1105532Y105554D01*
X1105839Y105606D01*
X1106222Y105503D01*
X1106490Y105244D01*
X1106567Y104934D01*
X1106529Y104624D01*
X1106375Y104366D01*
X1105609Y103849D01*
X1105264Y103488D01*
X1105034Y102971D01*
X1104957Y102506D01*
X1106567D01*
G01X1108134Y105089D02*
X1108364Y105399D01*
X1108632Y105554D01*
X1108939Y105606D01*
X1109322Y105503D01*
X1109590Y105244D01*
X1109667Y104934D01*
X1109629Y104624D01*
X1109475Y104366D01*
X1108709Y103849D01*
X1108364Y103488D01*
X1108134Y102971D01*
X1108057Y102506D01*
X1109667D01*
G01X1101895Y107006D02*
Y110106D01*
X1102854D01*
X1103160Y109951D01*
X1103352Y109744D01*
X1103429Y109331D01*
X1103352Y108918D01*
X1103122Y108659D01*
X1102854Y108504D01*
X1101895D01*
G01X1102854D02*
X1103429Y107006D01*
G01X1105034Y109589D02*
X1105264Y109899D01*
X1105532Y110054D01*
X1105839Y110106D01*
X1106222Y110003D01*
X1106490Y109744D01*
X1106567Y109434D01*
X1106529Y109124D01*
X1106375Y108866D01*
X1105609Y108349D01*
X1105264Y107988D01*
X1105034Y107471D01*
X1104957Y107006D01*
X1106567D01*
G01X1109322D02*
Y110106D01*
X1107904Y107884D01*
X1109820D01*
G01X1101895Y111306D02*
Y114406D01*
X1102854D01*
X1103160Y114251D01*
X1103352Y114044D01*
X1103429Y113631D01*
X1103352Y113218D01*
X1103122Y112959D01*
X1102854Y112804D01*
X1101895D01*
G01X1102854D02*
X1103429Y111306D01*
G01X1105034Y113889D02*
X1105264Y114199D01*
X1105532Y114354D01*
X1105839Y114406D01*
X1106222Y114303D01*
X1106490Y114044D01*
X1106567Y113734D01*
X1106529Y113424D01*
X1106375Y113166D01*
X1105609Y112649D01*
X1105264Y112288D01*
X1105034Y111771D01*
X1104957Y111306D01*
X1106567D01*
G01X1108134Y112598D02*
X1108402Y112959D01*
X1108632Y113166D01*
X1108939Y113269D01*
X1109207Y113166D01*
X1109399Y112959D01*
X1109552Y112649D01*
X1109590Y112288D01*
X1109552Y111978D01*
X1109399Y111668D01*
X1109169Y111409D01*
X1108900Y111306D01*
X1108594Y111409D01*
X1108325Y111719D01*
X1108172Y112184D01*
X1108134Y112701D01*
X1108210Y113373D01*
X1108325Y113734D01*
X1108517Y114096D01*
X1108785Y114354D01*
X1109054Y114406D01*
X1109322Y114303D01*
X1109514Y114044D01*
G01X1101895Y115306D02*
Y118406D01*
X1102854D01*
X1103160Y118251D01*
X1103352Y118044D01*
X1103429Y117631D01*
X1103352Y117218D01*
X1103122Y116959D01*
X1102854Y116804D01*
X1101895D01*
G01X1102854D02*
X1103429Y115306D01*
G01X1104919Y115926D02*
X1105149Y115564D01*
X1105455Y115358D01*
X1105800Y115306D01*
X1106107Y115358D01*
X1106414Y115616D01*
X1106605Y115926D01*
X1106644Y116236D01*
X1106567Y116598D01*
X1106299Y116856D01*
X1106030Y116959D01*
X1105685D01*
G01X1106030D02*
X1106260Y117114D01*
X1106452Y117373D01*
X1106529Y117683D01*
X1106452Y117993D01*
X1106260Y118251D01*
X1105915Y118406D01*
X1105570Y118354D01*
X1105225Y118148D01*
G01X1108862Y118406D02*
X1108555Y118303D01*
X1108325Y118044D01*
X1108172Y117734D01*
X1108057Y117321D01*
X1108019Y116856D01*
X1108057Y116391D01*
X1108172Y115978D01*
X1108325Y115668D01*
X1108555Y115409D01*
X1108862Y115306D01*
X1109169Y115409D01*
X1109399Y115668D01*
X1109552Y115978D01*
X1109667Y116391D01*
X1109705Y116856D01*
X1109667Y117321D01*
X1109552Y117734D01*
X1109399Y118044D01*
X1109169Y118303D01*
X1108862Y118406D01*
G01X1111371Y103209D02*
Y106309D01*
X1112330D01*
X1112636Y106154D01*
X1112828Y105947D01*
X1112905Y105534D01*
X1112828Y105121D01*
X1112598Y104862D01*
X1112330Y104707D01*
X1111371D01*
G01X1112330D02*
X1112905Y103209D01*
G01X1115161D02*
X1115238Y103881D01*
X1115353Y104449D01*
X1115506Y104966D01*
X1115698Y105534D01*
X1116005Y106309D01*
X1114471D01*
G01X1117610Y105792D02*
X1117840Y106102D01*
X1118108Y106257D01*
X1118415Y106309D01*
X1118798Y106206D01*
X1119066Y105947D01*
X1119143Y105637D01*
X1119105Y105327D01*
X1118951Y105069D01*
X1118185Y104552D01*
X1117840Y104191D01*
X1117610Y103674D01*
X1117533Y103209D01*
X1119143D01*
G01X1127890Y98850D02*
X1124790D01*
Y99809D01*
X1124945Y100115D01*
X1125152Y100307D01*
X1125565Y100384D01*
X1125978Y100307D01*
X1126237Y100077D01*
X1126392Y99809D01*
Y98850D01*
G01Y99809D02*
X1127890Y100384D01*
G01X1127270Y101874D02*
X1127632Y102104D01*
X1127838Y102410D01*
X1127890Y102755D01*
X1127838Y103062D01*
X1127580Y103369D01*
X1127270Y103560D01*
X1126960Y103599D01*
X1126598Y103522D01*
X1126340Y103254D01*
X1126237Y102985D01*
Y102640D01*
G01Y102985D02*
X1126082Y103215D01*
X1125823Y103407D01*
X1125513Y103484D01*
X1125203Y103407D01*
X1124945Y103215D01*
X1124790Y102870D01*
X1124842Y102525D01*
X1125048Y102180D01*
G01X1126598Y105089D02*
X1126237Y105357D01*
X1126030Y105587D01*
X1125927Y105894D01*
X1126030Y106162D01*
X1126237Y106354D01*
X1126547Y106507D01*
X1126908Y106545D01*
X1127218Y106507D01*
X1127528Y106354D01*
X1127787Y106124D01*
X1127890Y105855D01*
X1127787Y105549D01*
X1127477Y105280D01*
X1127012Y105127D01*
X1126495Y105089D01*
X1125823Y105165D01*
X1125462Y105280D01*
X1125100Y105472D01*
X1124842Y105740D01*
X1124790Y106009D01*
X1124893Y106277D01*
X1125152Y106469D01*
G01X1132991Y98850D02*
X1129891D01*
Y99809D01*
X1130046Y100115D01*
X1130253Y100307D01*
X1130666Y100384D01*
X1131079Y100307D01*
X1131338Y100077D01*
X1131493Y99809D01*
Y98850D01*
G01Y99809D02*
X1132991Y100384D01*
G01X1131699Y101989D02*
X1131338Y102257D01*
X1131131Y102487D01*
X1131028Y102794D01*
X1131131Y103062D01*
X1131338Y103254D01*
X1131648Y103407D01*
X1132009Y103445D01*
X1132319Y103407D01*
X1132629Y103254D01*
X1132888Y103024D01*
X1132991Y102755D01*
X1132888Y102449D01*
X1132578Y102180D01*
X1132113Y102027D01*
X1131596Y101989D01*
X1130924Y102065D01*
X1130563Y102180D01*
X1130201Y102372D01*
X1129943Y102640D01*
X1129891Y102909D01*
X1129994Y103177D01*
X1130253Y103369D01*
G01X1132991Y105817D02*
X1129891D01*
X1130511Y105357D01*
G01X1132991D02*
Y106277D01*
G01X1137075Y98850D02*
X1133975D01*
Y99809D01*
X1134130Y100115D01*
X1134337Y100307D01*
X1134750Y100384D01*
X1135163Y100307D01*
X1135422Y100077D01*
X1135577Y99809D01*
Y98850D01*
G01Y99809D02*
X1137075Y100384D01*
G01X1135783Y101989D02*
X1135422Y102257D01*
X1135215Y102487D01*
X1135112Y102794D01*
X1135215Y103062D01*
X1135422Y103254D01*
X1135732Y103407D01*
X1136093Y103445D01*
X1136403Y103407D01*
X1136713Y103254D01*
X1136972Y103024D01*
X1137075Y102755D01*
X1136972Y102449D01*
X1136662Y102180D01*
X1136197Y102027D01*
X1135680Y101989D01*
X1135008Y102065D01*
X1134647Y102180D01*
X1134285Y102372D01*
X1134027Y102640D01*
X1133975Y102909D01*
X1134078Y103177D01*
X1134337Y103369D01*
G01X1133975Y105817D02*
X1134078Y105510D01*
X1134337Y105280D01*
X1134647Y105127D01*
X1135060Y105012D01*
X1135525Y104974D01*
X1135990Y105012D01*
X1136403Y105127D01*
X1136713Y105280D01*
X1136972Y105510D01*
X1137075Y105817D01*
X1136972Y106124D01*
X1136713Y106354D01*
X1136403Y106507D01*
X1135990Y106622D01*
X1135525Y106660D01*
X1135060Y106622D01*
X1134647Y106507D01*
X1134337Y106354D01*
X1134078Y106124D01*
X1133975Y105817D01*
G01X1123791Y98850D02*
X1120691D01*
Y99809D01*
X1120846Y100115D01*
X1121053Y100307D01*
X1121466Y100384D01*
X1121879Y100307D01*
X1122138Y100077D01*
X1122293Y99809D01*
Y98850D01*
G01Y99809D02*
X1123791Y100384D01*
G01Y102640D02*
X1123119Y102717D01*
X1122551Y102832D01*
X1122034Y102985D01*
X1121466Y103177D01*
X1120691Y103484D01*
Y101950D01*
G01X1123791Y106277D02*
X1120691D01*
X1122913Y104859D01*
Y106775D01*
G01X1124657Y120853D02*
X1124810Y121008D01*
X1124925Y121267D01*
X1125002Y121628D01*
X1124925Y121938D01*
X1124772Y122145D01*
X1124503Y122300D01*
X1123468D01*
Y119200D01*
X1124733D01*
X1125002Y119407D01*
X1125155Y119717D01*
X1125232Y120078D01*
X1125155Y120440D01*
X1124925Y120750D01*
X1124657Y120853D01*
X1123468D01*
G01X1119000Y124300D02*
X1119100D01*
Y117100D01*
X1128600D01*
Y124400D01*
G01X1155886Y41850D02*
Y-127559D01*
X1197816D01*
Y83189D01*
X1155886D01*
Y41850D01*
G01Y-9842D02*
X1197816D01*
G01X1154255Y40609D02*
Y43709D01*
X1153795Y43089D01*
G01Y40609D02*
X1154715D01*
G01X1141091Y98850D02*
X1137991D01*
Y99809D01*
X1138146Y100115D01*
X1138353Y100307D01*
X1138766Y100384D01*
X1139179Y100307D01*
X1139438Y100077D01*
X1139593Y99809D01*
Y98850D01*
G01Y99809D02*
X1141091Y100384D01*
G01X1139799Y101989D02*
X1139438Y102257D01*
X1139231Y102487D01*
X1139128Y102794D01*
X1139231Y103062D01*
X1139438Y103254D01*
X1139748Y103407D01*
X1140109Y103445D01*
X1140419Y103407D01*
X1140729Y103254D01*
X1140988Y103024D01*
X1141091Y102755D01*
X1140988Y102449D01*
X1140678Y102180D01*
X1140213Y102027D01*
X1139696Y101989D01*
X1139024Y102065D01*
X1138663Y102180D01*
X1138301Y102372D01*
X1138043Y102640D01*
X1137991Y102909D01*
X1138094Y103177D01*
X1138353Y103369D01*
G01X1141091Y106277D02*
X1137991D01*
X1140213Y104859D01*
Y106775D01*
G01X1145007Y98850D02*
X1141907D01*
Y99809D01*
X1142062Y100115D01*
X1142269Y100307D01*
X1142682Y100384D01*
X1143095Y100307D01*
X1143354Y100077D01*
X1143509Y99809D01*
Y98850D01*
G01Y99809D02*
X1145007Y100384D01*
G01X1143715Y101989D02*
X1143354Y102257D01*
X1143147Y102487D01*
X1143044Y102794D01*
X1143147Y103062D01*
X1143354Y103254D01*
X1143664Y103407D01*
X1144025Y103445D01*
X1144335Y103407D01*
X1144645Y103254D01*
X1144904Y103024D01*
X1145007Y102755D01*
X1144904Y102449D01*
X1144594Y102180D01*
X1144129Y102027D01*
X1143612Y101989D01*
X1142940Y102065D01*
X1142579Y102180D01*
X1142217Y102372D01*
X1141959Y102640D01*
X1141907Y102909D01*
X1142010Y103177D01*
X1142269Y103369D01*
G01X1144542Y104974D02*
X1144800Y105204D01*
X1144955Y105472D01*
X1145007Y105817D01*
X1144904Y106162D01*
X1144697Y106430D01*
X1144335Y106622D01*
X1143922Y106660D01*
X1143509Y106584D01*
X1143250Y106392D01*
X1143044Y106124D01*
X1142992Y105855D01*
X1143044Y105587D01*
X1143250Y105242D01*
X1141907Y105357D01*
Y106392D01*
G01X1149391Y98850D02*
X1146291D01*
Y99809D01*
X1146446Y100115D01*
X1146653Y100307D01*
X1147066Y100384D01*
X1147479Y100307D01*
X1147738Y100077D01*
X1147893Y99809D01*
Y98850D01*
G01Y99809D02*
X1149391Y100384D01*
G01Y102640D02*
X1148719Y102717D01*
X1148151Y102832D01*
X1147634Y102985D01*
X1147066Y103177D01*
X1146291Y103484D01*
Y101950D01*
G01X1149391Y105817D02*
X1146291D01*
X1146911Y105357D01*
G01X1149391D02*
Y106277D01*
G01X1151047Y99009D02*
Y102109D01*
X1152006D01*
X1152312Y101954D01*
X1152504Y101747D01*
X1152581Y101334D01*
X1152504Y100921D01*
X1152274Y100662D01*
X1152006Y100507D01*
X1151047D01*
G01X1152006D02*
X1152581Y99009D01*
G01X1154837D02*
X1154914Y99681D01*
X1155029Y100249D01*
X1155182Y100766D01*
X1155374Y101334D01*
X1155681Y102109D01*
X1154147D01*
G01X1157171Y99474D02*
X1157401Y99216D01*
X1157669Y99061D01*
X1158014Y99009D01*
X1158359Y99112D01*
X1158627Y99319D01*
X1158819Y99681D01*
X1158857Y100094D01*
X1158781Y100507D01*
X1158589Y100766D01*
X1158321Y100972D01*
X1158052Y101024D01*
X1157784Y100972D01*
X1157439Y100766D01*
X1157554Y102109D01*
X1158589D01*
G01X1155934Y85437D02*
X1156126Y85127D01*
X1156356Y84920D01*
X1156624Y84817D01*
X1156931Y84920D01*
X1157161Y85127D01*
X1157391Y85437D01*
X1157468Y85850D01*
Y87917D01*
G01X1158958Y85282D02*
X1159188Y85024D01*
X1159456Y84869D01*
X1159801Y84817D01*
X1160146Y84920D01*
X1160414Y85127D01*
X1160606Y85489D01*
X1160644Y85902D01*
X1160568Y86315D01*
X1160376Y86574D01*
X1160108Y86780D01*
X1159839Y86832D01*
X1159571Y86780D01*
X1159226Y86574D01*
X1159341Y87917D01*
X1160376D01*
G01X1151047Y111306D02*
Y114406D01*
X1152006D01*
X1152312Y114251D01*
X1152504Y114044D01*
X1152581Y113631D01*
X1152504Y113218D01*
X1152274Y112959D01*
X1152006Y112804D01*
X1151047D01*
G01X1152006D02*
X1152581Y111306D01*
G01X1154186Y113889D02*
X1154416Y114199D01*
X1154684Y114354D01*
X1154991Y114406D01*
X1155374Y114303D01*
X1155642Y114044D01*
X1155719Y113734D01*
X1155681Y113424D01*
X1155527Y113166D01*
X1154761Y112649D01*
X1154416Y112288D01*
X1154186Y111771D01*
X1154109Y111306D01*
X1155719D01*
G01X1157171Y111771D02*
X1157401Y111513D01*
X1157669Y111358D01*
X1158014Y111306D01*
X1158359Y111409D01*
X1158627Y111616D01*
X1158819Y111978D01*
X1158857Y112391D01*
X1158781Y112804D01*
X1158589Y113063D01*
X1158321Y113269D01*
X1158052Y113321D01*
X1157784Y113269D01*
X1157439Y113063D01*
X1157554Y114406D01*
X1158589D01*
G01X1151047Y107106D02*
Y110206D01*
X1152006D01*
X1152312Y110051D01*
X1152504Y109844D01*
X1152581Y109431D01*
X1152504Y109018D01*
X1152274Y108759D01*
X1152006Y108604D01*
X1151047D01*
G01X1152006D02*
X1152581Y107106D01*
G01X1154186Y109689D02*
X1154416Y109999D01*
X1154684Y110154D01*
X1154991Y110206D01*
X1155374Y110103D01*
X1155642Y109844D01*
X1155719Y109534D01*
X1155681Y109224D01*
X1155527Y108966D01*
X1154761Y108449D01*
X1154416Y108088D01*
X1154186Y107571D01*
X1154109Y107106D01*
X1155719D01*
G01X1157362Y107468D02*
X1157631Y107209D01*
X1157937Y107106D01*
X1158244Y107209D01*
X1158512Y107519D01*
X1158704Y107984D01*
X1158781Y108449D01*
Y109018D01*
X1158704Y109483D01*
X1158512Y109896D01*
X1158282Y110103D01*
X1158014Y110206D01*
X1157707Y110103D01*
X1157477Y109896D01*
X1157324Y109586D01*
X1157247Y109173D01*
X1157324Y108811D01*
X1157516Y108449D01*
X1157746Y108243D01*
X1158014Y108191D01*
X1158321Y108294D01*
X1158551Y108553D01*
X1158781Y109018D01*
G01X1151047Y103209D02*
Y106309D01*
X1152006D01*
X1152312Y106154D01*
X1152504Y105947D01*
X1152581Y105534D01*
X1152504Y105121D01*
X1152274Y104862D01*
X1152006Y104707D01*
X1151047D01*
G01X1152006D02*
X1152581Y103209D01*
G01X1154837D02*
X1154914Y103881D01*
X1155029Y104449D01*
X1155182Y104966D01*
X1155374Y105534D01*
X1155681Y106309D01*
X1154147D01*
G01X1158014D02*
X1157707Y106206D01*
X1157477Y105947D01*
X1157324Y105637D01*
X1157209Y105224D01*
X1157171Y104759D01*
X1157209Y104294D01*
X1157324Y103881D01*
X1157477Y103571D01*
X1157707Y103312D01*
X1158014Y103209D01*
X1158321Y103312D01*
X1158551Y103571D01*
X1158704Y103881D01*
X1158819Y104294D01*
X1158857Y104759D01*
X1158819Y105224D01*
X1158704Y105637D01*
X1158551Y105947D01*
X1158321Y106206D01*
X1158014Y106309D01*
G01X1151047Y119506D02*
Y122606D01*
X1152006D01*
X1152312Y122451D01*
X1152504Y122244D01*
X1152581Y121831D01*
X1152504Y121418D01*
X1152274Y121159D01*
X1152006Y121004D01*
X1151047D01*
G01X1152006D02*
X1152581Y119506D01*
G01X1154186Y122089D02*
X1154416Y122399D01*
X1154684Y122554D01*
X1154991Y122606D01*
X1155374Y122503D01*
X1155642Y122244D01*
X1155719Y121934D01*
X1155681Y121624D01*
X1155527Y121366D01*
X1154761Y120849D01*
X1154416Y120488D01*
X1154186Y119971D01*
X1154109Y119506D01*
X1155719D01*
G01X1158014D02*
Y122606D01*
X1157554Y121986D01*
G01Y119506D02*
X1158474D01*
G01X1151047Y115406D02*
Y118506D01*
X1152006D01*
X1152312Y118351D01*
X1152504Y118144D01*
X1152581Y117731D01*
X1152504Y117318D01*
X1152274Y117059D01*
X1152006Y116904D01*
X1151047D01*
G01X1152006D02*
X1152581Y115406D01*
G01X1154186Y117989D02*
X1154416Y118299D01*
X1154684Y118454D01*
X1154991Y118506D01*
X1155374Y118403D01*
X1155642Y118144D01*
X1155719Y117834D01*
X1155681Y117524D01*
X1155527Y117266D01*
X1154761Y116749D01*
X1154416Y116388D01*
X1154186Y115871D01*
X1154109Y115406D01*
X1155719D01*
G01X1157171Y116026D02*
X1157401Y115664D01*
X1157707Y115458D01*
X1158052Y115406D01*
X1158359Y115458D01*
X1158666Y115716D01*
X1158857Y116026D01*
X1158896Y116336D01*
X1158819Y116698D01*
X1158551Y116956D01*
X1158282Y117059D01*
X1157937D01*
G01X1158282D02*
X1158512Y117214D01*
X1158704Y117473D01*
X1158781Y117783D01*
X1158704Y118093D01*
X1158512Y118351D01*
X1158167Y118506D01*
X1157822Y118454D01*
X1157477Y118248D01*
G01X1256870Y-52954D02*
X1186594D01*
G01D02*
Y86022D01*
G01X1198405Y74212D02*
X1245059D01*
Y-41143D01*
X1198405D01*
Y74212D01*
G01X1191339Y18651D02*
Y21751D01*
X1192105D01*
X1192412Y21596D01*
X1192642Y21389D01*
X1192834Y21079D01*
X1192987Y20718D01*
X1193025Y20201D01*
X1192987Y19684D01*
X1192834Y19323D01*
X1192642Y19013D01*
X1192412Y18806D01*
X1192105Y18651D01*
X1191339D01*
G01X1194554Y21234D02*
X1194784Y21544D01*
X1195052Y21699D01*
X1195359Y21751D01*
X1195742Y21648D01*
X1196010Y21389D01*
X1196087Y21079D01*
X1196049Y20769D01*
X1195895Y20511D01*
X1195129Y19994D01*
X1194784Y19633D01*
X1194554Y19116D01*
X1194477Y18651D01*
X1196087D01*
G01X1191339Y10776D02*
Y13876D01*
X1192105D01*
X1192412Y13721D01*
X1192642Y13514D01*
X1192834Y13204D01*
X1192987Y12843D01*
X1193025Y12326D01*
X1192987Y11809D01*
X1192834Y11448D01*
X1192642Y11138D01*
X1192412Y10931D01*
X1192105Y10776D01*
X1191339D01*
G01X1194439Y11396D02*
X1194669Y11034D01*
X1194975Y10828D01*
X1195320Y10776D01*
X1195627Y10828D01*
X1195934Y11086D01*
X1196125Y11396D01*
X1196164Y11706D01*
X1196087Y12068D01*
X1195819Y12326D01*
X1195550Y12429D01*
X1195205D01*
G01X1195550D02*
X1195780Y12584D01*
X1195972Y12843D01*
X1196049Y13153D01*
X1195972Y13463D01*
X1195780Y13721D01*
X1195435Y13876D01*
X1195090Y13824D01*
X1194745Y13618D01*
G01X1191339Y26525D02*
Y29625D01*
X1192105D01*
X1192412Y29470D01*
X1192642Y29263D01*
X1192834Y28953D01*
X1192987Y28592D01*
X1193025Y28075D01*
X1192987Y27558D01*
X1192834Y27197D01*
X1192642Y26887D01*
X1192412Y26680D01*
X1192105Y26525D01*
X1191339D01*
G01X1195282D02*
Y29625D01*
X1194822Y29005D01*
G01Y26525D02*
X1195742D01*
G01X1191224Y42273D02*
X1192182Y45373D01*
X1193140Y42273D01*
G01X1192795Y43358D02*
X1191569D01*
G01X1194439Y42893D02*
X1194669Y42531D01*
X1194975Y42325D01*
X1195320Y42273D01*
X1195627Y42325D01*
X1195934Y42583D01*
X1196125Y42893D01*
X1196164Y43203D01*
X1196087Y43565D01*
X1195819Y43823D01*
X1195550Y43926D01*
X1195205D01*
G01X1195550D02*
X1195780Y44081D01*
X1195972Y44340D01*
X1196049Y44650D01*
X1195972Y44960D01*
X1195780Y45218D01*
X1195435Y45373D01*
X1195090Y45321D01*
X1194745Y45115D01*
G01X1191224Y50147D02*
X1192182Y53247D01*
X1193140Y50147D01*
G01X1192795Y51232D02*
X1191569D01*
G01X1194554Y52730D02*
X1194784Y53040D01*
X1195052Y53195D01*
X1195359Y53247D01*
X1195742Y53144D01*
X1196010Y52885D01*
X1196087Y52575D01*
X1196049Y52265D01*
X1195895Y52007D01*
X1195129Y51490D01*
X1194784Y51129D01*
X1194554Y50612D01*
X1194477Y50147D01*
X1196087D01*
G01X1203824Y75021D02*
X1204782Y78121D01*
X1205740Y75021D01*
G01X1205395Y76106D02*
X1204169D01*
G01X1207882Y75021D02*
Y78121D01*
X1207422Y77501D01*
G01Y75021D02*
X1208342D01*
G01X1186815Y87987D02*
X1187007Y87677D01*
X1187237Y87470D01*
X1187505Y87367D01*
X1187812Y87470D01*
X1188042Y87677D01*
X1188272Y87987D01*
X1188349Y88400D01*
Y90467D01*
G01X1190030Y87729D02*
X1190299Y87470D01*
X1190605Y87367D01*
X1190912Y87470D01*
X1191180Y87780D01*
X1191372Y88245D01*
X1191449Y88710D01*
Y89279D01*
X1191372Y89744D01*
X1191180Y90157D01*
X1190950Y90364D01*
X1190682Y90467D01*
X1190375Y90364D01*
X1190145Y90157D01*
X1189992Y89847D01*
X1189915Y89434D01*
X1189992Y89072D01*
X1190184Y88710D01*
X1190414Y88504D01*
X1190682Y88452D01*
X1190989Y88555D01*
X1191219Y88814D01*
X1191449Y89279D01*
G01X1195965Y78900D02*
Y85200D01*
X1197845D01*
X1198472Y84885D01*
X1198942Y84150D01*
X1199099Y83310D01*
X1198942Y82470D01*
X1198550Y81840D01*
X1197845Y81525D01*
X1195965D01*
G01X1202265Y78900D02*
Y85200D01*
X1204224D01*
X1204850Y84885D01*
X1205242Y84465D01*
X1205399Y83625D01*
X1205242Y82785D01*
X1204772Y82260D01*
X1204224Y81945D01*
X1202265D01*
G01X1204224D02*
X1205399Y78900D01*
G01X1211699D02*
X1208565D01*
Y85200D01*
X1211699D01*
G01X1210445Y82155D02*
X1208565D01*
G01X1214787Y79740D02*
X1215414Y79215D01*
X1216119Y78900D01*
X1216745D01*
X1217372Y79215D01*
X1217842Y79740D01*
X1218077Y80475D01*
X1217920Y81210D01*
X1217529Y81840D01*
X1216824Y82260D01*
X1215884Y82470D01*
X1215335Y82890D01*
X1215100Y83625D01*
X1215257Y84360D01*
X1215649Y84885D01*
X1216197Y85200D01*
X1216745D01*
X1217294Y84990D01*
X1217764Y84465D01*
G01X1221087Y79740D02*
X1221714Y79215D01*
X1222419Y78900D01*
X1223045D01*
X1223672Y79215D01*
X1224142Y79740D01*
X1224377Y80475D01*
X1224220Y81210D01*
X1223829Y81840D01*
X1223124Y82260D01*
X1222184Y82470D01*
X1221635Y82890D01*
X1221400Y83625D01*
X1221557Y84360D01*
X1221949Y84885D01*
X1222497Y85200D01*
X1223045D01*
X1223594Y84990D01*
X1224064Y84465D01*
G01X1228014Y81000D02*
X1230050D01*
G01X1233844Y78900D02*
Y85200D01*
X1236820D01*
G01X1235724Y82155D02*
X1233844D01*
G01X1240692Y85200D02*
X1242572D01*
G01X1241632D02*
Y78900D01*
G01X1240692D02*
X1242572D01*
G01X1247932Y85200D02*
Y78900D01*
G01X1246130Y85200D02*
X1249734D01*
G01X1186594Y86022D02*
X1256870D01*
G01X1195534Y99144D02*
X1195379Y98914D01*
X1195276Y98646D01*
Y98339D01*
X1195431Y97994D01*
X1195689Y97726D01*
X1195999Y97534D01*
X1196516Y97381D01*
X1196981Y97343D01*
X1197446Y97419D01*
X1197756Y97534D01*
X1198066Y97764D01*
X1198273Y98033D01*
X1198376Y98301D01*
Y98569D01*
X1198273Y98838D01*
X1198118Y99068D01*
X1197911Y99259D01*
G01X1198376Y101401D02*
X1195276D01*
X1195896Y100941D01*
G01X1198376D02*
Y101861D01*
G01X1195276Y104501D02*
X1195379Y104194D01*
X1195638Y103964D01*
X1195948Y103811D01*
X1196361Y103696D01*
X1196826Y103658D01*
X1197291Y103696D01*
X1197704Y103811D01*
X1198014Y103964D01*
X1198273Y104194D01*
X1198376Y104501D01*
X1198273Y104808D01*
X1198014Y105038D01*
X1197704Y105191D01*
X1197291Y105306D01*
X1196826Y105344D01*
X1196361Y105306D01*
X1195948Y105191D01*
X1195638Y105038D01*
X1195379Y104808D01*
X1195276Y104501D01*
G01X1200534Y99194D02*
X1200379Y98964D01*
X1200276Y98696D01*
Y98389D01*
X1200431Y98044D01*
X1200689Y97776D01*
X1200999Y97584D01*
X1201516Y97431D01*
X1201981Y97393D01*
X1202446Y97469D01*
X1202756Y97584D01*
X1203066Y97814D01*
X1203273Y98083D01*
X1203376Y98351D01*
Y98619D01*
X1203273Y98888D01*
X1203118Y99118D01*
X1202911Y99309D01*
G01X1203014Y100799D02*
X1203273Y101068D01*
X1203376Y101374D01*
X1203273Y101681D01*
X1202963Y101949D01*
X1202498Y102141D01*
X1202033Y102218D01*
X1201464D01*
X1200999Y102141D01*
X1200586Y101949D01*
X1200379Y101719D01*
X1200276Y101451D01*
X1200379Y101144D01*
X1200586Y100914D01*
X1200896Y100761D01*
X1201309Y100684D01*
X1201671Y100761D01*
X1202033Y100953D01*
X1202239Y101183D01*
X1202291Y101451D01*
X1202188Y101758D01*
X1201929Y101988D01*
X1201464Y102218D01*
G01X1195395Y112106D02*
Y115206D01*
X1196354D01*
X1196660Y115051D01*
X1196852Y114844D01*
X1196929Y114431D01*
X1196852Y114018D01*
X1196622Y113759D01*
X1196354Y113604D01*
X1195395D01*
G01X1196354D02*
X1196929Y112106D01*
G01X1198419Y112571D02*
X1198649Y112313D01*
X1198917Y112158D01*
X1199262Y112106D01*
X1199607Y112209D01*
X1199875Y112416D01*
X1200067Y112778D01*
X1200105Y113191D01*
X1200029Y113604D01*
X1199837Y113863D01*
X1199569Y114069D01*
X1199300Y114121D01*
X1199032Y114069D01*
X1198687Y113863D01*
X1198802Y115206D01*
X1199837D01*
G01X1201634Y114689D02*
X1201864Y114999D01*
X1202132Y115154D01*
X1202439Y115206D01*
X1202822Y115103D01*
X1203090Y114844D01*
X1203167Y114534D01*
X1203129Y114224D01*
X1202975Y113966D01*
X1202209Y113449D01*
X1201864Y113088D01*
X1201634Y112571D01*
X1201557Y112106D01*
X1203167D01*
G01X1195195Y107406D02*
Y110506D01*
X1196154D01*
X1196460Y110351D01*
X1196652Y110144D01*
X1196729Y109731D01*
X1196652Y109318D01*
X1196422Y109059D01*
X1196154Y108904D01*
X1195195D01*
G01X1196154D02*
X1196729Y107406D01*
G01X1198219Y107871D02*
X1198449Y107613D01*
X1198717Y107458D01*
X1199062Y107406D01*
X1199407Y107509D01*
X1199675Y107716D01*
X1199867Y108078D01*
X1199905Y108491D01*
X1199829Y108904D01*
X1199637Y109163D01*
X1199369Y109369D01*
X1199100Y109421D01*
X1198832Y109369D01*
X1198487Y109163D01*
X1198602Y110506D01*
X1199637D01*
G01X1201319Y108026D02*
X1201549Y107664D01*
X1201855Y107458D01*
X1202200Y107406D01*
X1202507Y107458D01*
X1202814Y107716D01*
X1203005Y108026D01*
X1203044Y108336D01*
X1202967Y108698D01*
X1202699Y108956D01*
X1202430Y109059D01*
X1202085D01*
G01X1202430D02*
X1202660Y109214D01*
X1202852Y109473D01*
X1202929Y109783D01*
X1202852Y110093D01*
X1202660Y110351D01*
X1202315Y110506D01*
X1201970Y110454D01*
X1201625Y110248D01*
G01X1195195Y121006D02*
Y124106D01*
X1196154D01*
X1196460Y123951D01*
X1196652Y123744D01*
X1196729Y123331D01*
X1196652Y122918D01*
X1196422Y122659D01*
X1196154Y122504D01*
X1195195D01*
G01X1196154D02*
X1196729Y121006D01*
G01X1198219Y121471D02*
X1198449Y121213D01*
X1198717Y121058D01*
X1199062Y121006D01*
X1199407Y121109D01*
X1199675Y121316D01*
X1199867Y121678D01*
X1199905Y122091D01*
X1199829Y122504D01*
X1199637Y122763D01*
X1199369Y122969D01*
X1199100Y123021D01*
X1198832Y122969D01*
X1198487Y122763D01*
X1198602Y124106D01*
X1199637D01*
G01X1202622Y121006D02*
Y124106D01*
X1201204Y121884D01*
X1203120D01*
G01X1195295Y116524D02*
Y119624D01*
X1196254D01*
X1196560Y119469D01*
X1196752Y119262D01*
X1196829Y118849D01*
X1196752Y118436D01*
X1196522Y118177D01*
X1196254Y118022D01*
X1195295D01*
G01X1196254D02*
X1196829Y116524D01*
G01X1198319Y116989D02*
X1198549Y116731D01*
X1198817Y116576D01*
X1199162Y116524D01*
X1199507Y116627D01*
X1199775Y116834D01*
X1199967Y117196D01*
X1200005Y117609D01*
X1199929Y118022D01*
X1199737Y118281D01*
X1199469Y118487D01*
X1199200Y118539D01*
X1198932Y118487D01*
X1198587Y118281D01*
X1198702Y119624D01*
X1199737D01*
G01X1201419Y116989D02*
X1201649Y116731D01*
X1201917Y116576D01*
X1202262Y116524D01*
X1202607Y116627D01*
X1202875Y116834D01*
X1203067Y117196D01*
X1203105Y117609D01*
X1203029Y118022D01*
X1202837Y118281D01*
X1202569Y118487D01*
X1202300Y118539D01*
X1202032Y118487D01*
X1201687Y118281D01*
X1201802Y119624D01*
X1202837D01*
G01X1197900Y129283D02*
X1201000D01*
Y130817D01*
G01X1199708Y132422D02*
X1199347Y132690D01*
X1199140Y132920D01*
X1199037Y133227D01*
X1199140Y133495D01*
X1199347Y133687D01*
X1199657Y133840D01*
X1200018Y133878D01*
X1200328Y133840D01*
X1200638Y133687D01*
X1200897Y133457D01*
X1201000Y133188D01*
X1200897Y132882D01*
X1200587Y132613D01*
X1200122Y132460D01*
X1199605Y132422D01*
X1198933Y132498D01*
X1198572Y132613D01*
X1198210Y132805D01*
X1197952Y133073D01*
X1197900Y133342D01*
X1198003Y133610D01*
X1198262Y133802D01*
G01X1193300Y128983D02*
X1196400D01*
Y130517D01*
G01Y132850D02*
X1196348Y133118D01*
X1196193Y133425D01*
X1195935Y133617D01*
X1195573Y133693D01*
X1195212Y133617D01*
X1194902Y133387D01*
X1194747Y133042D01*
Y132658D01*
X1194643Y132428D01*
X1194385Y132237D01*
X1194023Y132160D01*
X1193662Y132275D01*
X1193403Y132543D01*
X1193300Y132850D01*
X1193403Y133157D01*
X1193662Y133425D01*
X1194023Y133540D01*
X1194385Y133463D01*
X1194643Y133272D01*
X1194747Y133042D01*
Y132658D01*
X1194902Y132313D01*
X1195212Y132083D01*
X1195573Y132007D01*
X1195935Y132083D01*
X1196193Y132275D01*
X1196348Y132582D01*
X1196400Y132850D01*
G01X1209300Y133000D02*
X1202700D01*
G01X1209300Y140000D02*
X1202700D01*
G01X1209300Y125000D02*
X1202700D01*
G01X1202600D02*
Y140000D01*
G01X1209300Y132000D02*
X1202700D01*
G01X1185253Y140981D02*
Y144081D01*
G01X1186863D02*
Y140981D01*
G01Y142531D02*
X1185253D01*
G01X1188430Y142273D02*
X1188698Y142634D01*
X1188928Y142841D01*
X1189235Y142944D01*
X1189503Y142841D01*
X1189695Y142634D01*
X1189848Y142324D01*
X1189886Y141963D01*
X1189848Y141653D01*
X1189695Y141343D01*
X1189465Y141084D01*
X1189196Y140981D01*
X1188890Y141084D01*
X1188621Y141394D01*
X1188468Y141859D01*
X1188430Y142376D01*
X1188506Y143048D01*
X1188621Y143409D01*
X1188813Y143771D01*
X1189081Y144029D01*
X1189350Y144081D01*
X1189618Y143978D01*
X1189810Y143719D01*
G01X1205567Y99494D02*
X1205412Y99264D01*
X1205309Y98996D01*
Y98689D01*
X1205464Y98344D01*
X1205722Y98076D01*
X1206032Y97884D01*
X1206549Y97731D01*
X1207014Y97693D01*
X1207479Y97769D01*
X1207789Y97884D01*
X1208099Y98114D01*
X1208306Y98383D01*
X1208409Y98651D01*
Y98919D01*
X1208306Y99188D01*
X1208151Y99418D01*
X1207944Y99609D01*
G01X1208409Y101751D02*
X1205309D01*
X1205929Y101291D01*
G01X1208409D02*
Y102211D01*
G01X1205826Y104123D02*
X1205516Y104353D01*
X1205361Y104621D01*
X1205309Y104928D01*
X1205412Y105311D01*
X1205671Y105579D01*
X1205981Y105656D01*
X1206291Y105618D01*
X1206549Y105464D01*
X1207066Y104698D01*
X1207427Y104353D01*
X1207944Y104123D01*
X1208409Y104046D01*
Y105656D01*
G01X1230924Y95099D02*
Y88899D01*
X1227724D01*
Y95099D01*
X1230924D01*
G01X1210967Y99394D02*
X1210812Y99164D01*
X1210709Y98896D01*
Y98589D01*
X1210864Y98244D01*
X1211122Y97976D01*
X1211432Y97784D01*
X1211949Y97631D01*
X1212414Y97593D01*
X1212879Y97669D01*
X1213189Y97784D01*
X1213499Y98014D01*
X1213706Y98283D01*
X1213809Y98551D01*
Y98819D01*
X1213706Y99088D01*
X1213551Y99318D01*
X1213344Y99509D01*
G01X1213809Y101651D02*
X1210709D01*
X1211329Y101191D01*
G01X1213809D02*
Y102111D01*
G01Y104751D02*
X1210709D01*
X1211329Y104291D01*
G01X1213809D02*
Y105211D01*
G01X1219624Y97699D02*
Y87499D01*
X1215024D01*
Y97699D01*
X1219624D01*
G01Y92599D02*
X1215024D01*
G01X1225724D02*
X1221124D01*
G01X1225724Y97699D02*
Y87499D01*
X1221124D01*
Y97699D01*
X1225724D01*
G01X1224788Y106761D02*
X1218588D01*
Y109961D01*
X1224788D01*
Y106761D01*
G01Y101261D02*
X1218588D01*
Y104461D01*
X1224788D01*
Y101261D01*
G01Y117961D02*
X1218588D01*
Y121161D01*
X1224788D01*
Y117961D01*
G01Y112443D02*
X1218588D01*
Y115643D01*
X1224788D01*
Y112443D01*
G01X1207143Y120828D02*
Y123928D01*
X1208102D01*
X1208408Y123773D01*
X1208600Y123566D01*
X1208677Y123153D01*
X1208600Y122740D01*
X1208370Y122481D01*
X1208102Y122326D01*
X1207143D01*
G01X1208102D02*
X1208677Y120828D01*
G01X1211010D02*
Y123928D01*
X1210550Y123308D01*
G01Y120828D02*
X1211470D01*
G01X1214110D02*
X1214378Y120880D01*
X1214685Y121035D01*
X1214877Y121293D01*
X1214953Y121655D01*
X1214877Y122016D01*
X1214647Y122326D01*
X1214302Y122481D01*
X1213918D01*
X1213688Y122585D01*
X1213497Y122843D01*
X1213420Y123205D01*
X1213535Y123566D01*
X1213803Y123825D01*
X1214110Y123928D01*
X1214417Y123825D01*
X1214685Y123566D01*
X1214800Y123205D01*
X1214723Y122843D01*
X1214532Y122585D01*
X1214302Y122481D01*
X1213918D01*
X1213573Y122326D01*
X1213343Y122016D01*
X1213267Y121655D01*
X1213343Y121293D01*
X1213535Y121035D01*
X1213842Y120880D01*
X1214110Y120828D01*
G01X1207043Y116410D02*
Y119510D01*
X1208002D01*
X1208308Y119355D01*
X1208500Y119148D01*
X1208577Y118735D01*
X1208500Y118322D01*
X1208270Y118063D01*
X1208002Y117908D01*
X1207043D01*
G01X1208002D02*
X1208577Y116410D01*
G01X1210182Y118993D02*
X1210412Y119303D01*
X1210680Y119458D01*
X1210987Y119510D01*
X1211370Y119407D01*
X1211638Y119148D01*
X1211715Y118838D01*
X1211677Y118528D01*
X1211523Y118270D01*
X1210757Y117753D01*
X1210412Y117392D01*
X1210182Y116875D01*
X1210105Y116410D01*
X1211715D01*
G01X1214010Y119510D02*
X1213703Y119407D01*
X1213473Y119148D01*
X1213320Y118838D01*
X1213205Y118425D01*
X1213167Y117960D01*
X1213205Y117495D01*
X1213320Y117082D01*
X1213473Y116772D01*
X1213703Y116513D01*
X1214010Y116410D01*
X1214317Y116513D01*
X1214547Y116772D01*
X1214700Y117082D01*
X1214815Y117495D01*
X1214853Y117960D01*
X1214815Y118425D01*
X1214700Y118838D01*
X1214547Y119148D01*
X1214317Y119407D01*
X1214010Y119510D01*
G01X1206943Y112028D02*
Y115128D01*
X1207902D01*
X1208208Y114973D01*
X1208400Y114766D01*
X1208477Y114353D01*
X1208400Y113940D01*
X1208170Y113681D01*
X1207902Y113526D01*
X1206943D01*
G01X1207902D02*
X1208477Y112028D01*
G01X1210082Y114611D02*
X1210312Y114921D01*
X1210580Y115076D01*
X1210887Y115128D01*
X1211270Y115025D01*
X1211538Y114766D01*
X1211615Y114456D01*
X1211577Y114146D01*
X1211423Y113888D01*
X1210657Y113371D01*
X1210312Y113010D01*
X1210082Y112493D01*
X1210005Y112028D01*
X1211615D01*
G01X1213910D02*
X1214178Y112080D01*
X1214485Y112235D01*
X1214677Y112493D01*
X1214753Y112855D01*
X1214677Y113216D01*
X1214447Y113526D01*
X1214102Y113681D01*
X1213718D01*
X1213488Y113785D01*
X1213297Y114043D01*
X1213220Y114405D01*
X1213335Y114766D01*
X1213603Y115025D01*
X1213910Y115128D01*
X1214217Y115025D01*
X1214485Y114766D01*
X1214600Y114405D01*
X1214523Y114043D01*
X1214332Y113785D01*
X1214102Y113681D01*
X1213718D01*
X1213373Y113526D01*
X1213143Y113216D01*
X1213067Y112855D01*
X1213143Y112493D01*
X1213335Y112235D01*
X1213642Y112080D01*
X1213910Y112028D01*
G01X1206943Y107628D02*
Y110728D01*
X1207902D01*
X1208208Y110573D01*
X1208400Y110366D01*
X1208477Y109953D01*
X1208400Y109540D01*
X1208170Y109281D01*
X1207902Y109126D01*
X1206943D01*
G01X1207902D02*
X1208477Y107628D01*
G01X1209967Y108248D02*
X1210197Y107886D01*
X1210503Y107680D01*
X1210848Y107628D01*
X1211155Y107680D01*
X1211462Y107938D01*
X1211653Y108248D01*
X1211692Y108558D01*
X1211615Y108920D01*
X1211347Y109178D01*
X1211078Y109281D01*
X1210733D01*
G01X1211078D02*
X1211308Y109436D01*
X1211500Y109695D01*
X1211577Y110005D01*
X1211500Y110315D01*
X1211308Y110573D01*
X1210963Y110728D01*
X1210618Y110676D01*
X1210273Y110470D01*
G01X1213182Y110211D02*
X1213412Y110521D01*
X1213680Y110676D01*
X1213987Y110728D01*
X1214370Y110625D01*
X1214638Y110366D01*
X1214715Y110056D01*
X1214677Y109746D01*
X1214523Y109488D01*
X1213757Y108971D01*
X1213412Y108610D01*
X1213182Y108093D01*
X1213105Y107628D01*
X1214715D01*
G01X1213965Y146355D02*
X1214195Y146665D01*
X1214463Y146820D01*
X1214770Y146872D01*
X1215153Y146769D01*
X1215421Y146510D01*
X1215498Y146200D01*
X1215460Y145890D01*
X1215306Y145632D01*
X1214540Y145115D01*
X1214195Y144754D01*
X1213965Y144237D01*
X1213888Y143772D01*
X1215498D01*
G01X1236177Y139761D02*
X1219638D01*
Y148029D01*
X1236177D01*
Y139761D01*
G01X1217400Y133100D02*
X1210800D01*
G01X1217400Y140100D02*
X1210800D01*
G01X1217400Y125100D02*
X1210800D01*
G01X1210700D02*
Y140100D01*
G01X1217400Y132100D02*
X1210800D01*
G01X1217500Y140100D02*
Y125100D01*
G01X1209400Y140000D02*
Y125000D01*
G01X1236400Y129642D02*
Y122842D01*
X1221400D01*
Y129642D01*
X1236400D01*
G01Y137942D02*
Y131142D01*
X1221400D01*
Y137942D01*
X1236400D01*
G01X1214350Y154425D02*
X1214580Y154735D01*
X1214848Y154890D01*
X1215155Y154942D01*
X1215538Y154839D01*
X1215806Y154580D01*
X1215883Y154270D01*
X1215845Y153960D01*
X1215691Y153702D01*
X1214925Y153185D01*
X1214580Y152824D01*
X1214350Y152307D01*
X1214273Y151842D01*
X1215883D01*
G01X1236282Y149471D02*
X1219743D01*
Y157739D01*
X1236282D01*
Y149471D01*
G01X1223883Y159842D02*
Y162942D01*
X1224842D01*
X1225148Y162787D01*
X1225340Y162580D01*
X1225417Y162167D01*
X1225340Y161754D01*
X1225110Y161495D01*
X1224842Y161340D01*
X1223883D01*
G01X1224842D02*
X1225417Y159842D01*
G01X1227750D02*
X1228018Y159894D01*
X1228325Y160049D01*
X1228517Y160307D01*
X1228593Y160669D01*
X1228517Y161030D01*
X1228287Y161340D01*
X1227942Y161495D01*
X1227558D01*
X1227328Y161599D01*
X1227137Y161857D01*
X1227060Y162219D01*
X1227175Y162580D01*
X1227443Y162839D01*
X1227750Y162942D01*
X1228057Y162839D01*
X1228325Y162580D01*
X1228440Y162219D01*
X1228363Y161857D01*
X1228172Y161599D01*
X1227942Y161495D01*
X1227558D01*
X1227213Y161340D01*
X1226983Y161030D01*
X1226907Y160669D01*
X1226983Y160307D01*
X1227175Y160049D01*
X1227482Y159894D01*
X1227750Y159842D01*
G01X1230007Y160462D02*
X1230237Y160100D01*
X1230543Y159894D01*
X1230888Y159842D01*
X1231195Y159894D01*
X1231502Y160152D01*
X1231693Y160462D01*
X1231732Y160772D01*
X1231655Y161134D01*
X1231387Y161392D01*
X1231118Y161495D01*
X1230773D01*
G01X1231118D02*
X1231348Y161650D01*
X1231540Y161909D01*
X1231617Y162219D01*
X1231540Y162529D01*
X1231348Y162787D01*
X1231003Y162942D01*
X1230658Y162890D01*
X1230313Y162684D01*
G01X1223883Y164842D02*
Y167942D01*
X1224842D01*
X1225148Y167787D01*
X1225340Y167580D01*
X1225417Y167167D01*
X1225340Y166754D01*
X1225110Y166495D01*
X1224842Y166340D01*
X1223883D01*
G01X1224842D02*
X1225417Y164842D01*
G01X1227750D02*
X1228018Y164894D01*
X1228325Y165049D01*
X1228517Y165307D01*
X1228593Y165669D01*
X1228517Y166030D01*
X1228287Y166340D01*
X1227942Y166495D01*
X1227558D01*
X1227328Y166599D01*
X1227137Y166857D01*
X1227060Y167219D01*
X1227175Y167580D01*
X1227443Y167839D01*
X1227750Y167942D01*
X1228057Y167839D01*
X1228325Y167580D01*
X1228440Y167219D01*
X1228363Y166857D01*
X1228172Y166599D01*
X1227942Y166495D01*
X1227558D01*
X1227213Y166340D01*
X1226983Y166030D01*
X1226907Y165669D01*
X1226983Y165307D01*
X1227175Y165049D01*
X1227482Y164894D01*
X1227750Y164842D01*
G01X1230122Y167425D02*
X1230352Y167735D01*
X1230620Y167890D01*
X1230927Y167942D01*
X1231310Y167839D01*
X1231578Y167580D01*
X1231655Y167270D01*
X1231617Y166960D01*
X1231463Y166702D01*
X1230697Y166185D01*
X1230352Y165824D01*
X1230122Y165307D01*
X1230045Y164842D01*
X1231655D01*
G01X1223916Y169472D02*
Y172572D01*
X1225372D01*
G01X1224836Y171074D02*
X1223916D01*
G01X1226939Y169885D02*
X1227246Y169627D01*
X1227591Y169472D01*
X1227897D01*
X1228204Y169627D01*
X1228434Y169885D01*
X1228549Y170247D01*
X1228472Y170609D01*
X1228281Y170919D01*
X1227936Y171125D01*
X1227476Y171229D01*
X1227207Y171435D01*
X1227092Y171797D01*
X1227169Y172159D01*
X1227361Y172417D01*
X1227629Y172572D01*
X1227897D01*
X1228166Y172469D01*
X1228396Y172210D01*
G01X1230116Y170764D02*
X1230384Y171125D01*
X1230614Y171332D01*
X1230921Y171435D01*
X1231189Y171332D01*
X1231381Y171125D01*
X1231534Y170815D01*
X1231572Y170454D01*
X1231534Y170144D01*
X1231381Y169834D01*
X1231151Y169575D01*
X1230882Y169472D01*
X1230576Y169575D01*
X1230307Y169885D01*
X1230154Y170350D01*
X1230116Y170867D01*
X1230192Y171539D01*
X1230307Y171900D01*
X1230499Y172262D01*
X1230767Y172520D01*
X1231036Y172572D01*
X1231304Y172469D01*
X1231496Y172210D01*
G01X1223701Y174042D02*
Y177142D01*
X1225157D01*
G01X1224621Y175644D02*
X1223701D01*
G01X1226724Y174455D02*
X1227031Y174197D01*
X1227376Y174042D01*
X1227682D01*
X1227989Y174197D01*
X1228219Y174455D01*
X1228334Y174817D01*
X1228257Y175179D01*
X1228066Y175489D01*
X1227721Y175695D01*
X1227261Y175799D01*
X1226992Y176005D01*
X1226877Y176367D01*
X1226954Y176729D01*
X1227146Y176987D01*
X1227414Y177142D01*
X1227682D01*
X1227951Y177039D01*
X1228181Y176780D01*
G01X1230629Y174042D02*
X1230897Y174094D01*
X1231204Y174249D01*
X1231396Y174507D01*
X1231472Y174869D01*
X1231396Y175230D01*
X1231166Y175540D01*
X1230821Y175695D01*
X1230437D01*
X1230207Y175799D01*
X1230016Y176057D01*
X1229939Y176419D01*
X1230054Y176780D01*
X1230322Y177039D01*
X1230629Y177142D01*
X1230936Y177039D01*
X1231204Y176780D01*
X1231319Y176419D01*
X1231242Y176057D01*
X1231051Y175799D01*
X1230821Y175695D01*
X1230437D01*
X1230092Y175540D01*
X1229862Y175230D01*
X1229786Y174869D01*
X1229862Y174507D01*
X1230054Y174249D01*
X1230361Y174094D01*
X1230629Y174042D01*
G01X1249025Y21493D02*
X1248795Y21648D01*
X1248527Y21751D01*
X1248220D01*
X1247875Y21596D01*
X1247607Y21338D01*
X1247415Y21028D01*
X1247262Y20511D01*
X1247224Y20046D01*
X1247300Y19581D01*
X1247415Y19271D01*
X1247645Y18961D01*
X1247914Y18754D01*
X1248182Y18651D01*
X1248450D01*
X1248719Y18754D01*
X1248949Y18909D01*
X1249140Y19116D01*
G01X1250554Y21234D02*
X1250784Y21544D01*
X1251052Y21699D01*
X1251359Y21751D01*
X1251742Y21648D01*
X1252010Y21389D01*
X1252087Y21079D01*
X1252049Y20769D01*
X1251895Y20511D01*
X1251129Y19994D01*
X1250784Y19633D01*
X1250554Y19116D01*
X1250477Y18651D01*
X1252087D01*
G01X1248425Y14518D02*
X1248195Y14673D01*
X1247927Y14776D01*
X1247620D01*
X1247275Y14621D01*
X1247007Y14363D01*
X1246815Y14053D01*
X1246662Y13536D01*
X1246624Y13071D01*
X1246700Y12606D01*
X1246815Y12296D01*
X1247045Y11986D01*
X1247314Y11779D01*
X1247582Y11676D01*
X1247850D01*
X1248119Y11779D01*
X1248349Y11934D01*
X1248540Y12141D01*
G01X1249839Y12296D02*
X1250069Y11934D01*
X1250375Y11728D01*
X1250720Y11676D01*
X1251027Y11728D01*
X1251334Y11986D01*
X1251525Y12296D01*
X1251564Y12606D01*
X1251487Y12968D01*
X1251219Y13226D01*
X1250950Y13329D01*
X1250605D01*
G01X1250950D02*
X1251180Y13484D01*
X1251372Y13743D01*
X1251449Y14053D01*
X1251372Y14363D01*
X1251180Y14621D01*
X1250835Y14776D01*
X1250490Y14724D01*
X1250145Y14518D01*
G01X1248825Y28267D02*
X1248595Y28422D01*
X1248327Y28525D01*
X1248020D01*
X1247675Y28370D01*
X1247407Y28112D01*
X1247215Y27802D01*
X1247062Y27285D01*
X1247024Y26820D01*
X1247100Y26355D01*
X1247215Y26045D01*
X1247445Y25735D01*
X1247714Y25528D01*
X1247982Y25425D01*
X1248250D01*
X1248519Y25528D01*
X1248749Y25683D01*
X1248940Y25890D01*
G01X1251082Y25425D02*
Y28525D01*
X1250622Y27905D01*
G01Y25425D02*
X1251542D01*
G01X1292400Y17698D02*
X1237973D01*
G01D02*
Y235414D01*
X1325571D01*
Y17698D01*
X1321000D01*
G01X1261323Y29509D02*
X1249784D01*
Y223603D01*
X1313760D01*
G01X1247200Y50389D02*
X1247045Y50542D01*
X1246786Y50657D01*
X1246425Y50734D01*
X1246115Y50657D01*
X1245908Y50504D01*
X1245753Y50235D01*
Y49200D01*
X1248853D01*
Y50465D01*
X1248646Y50734D01*
X1248336Y50887D01*
X1247975Y50964D01*
X1247613Y50887D01*
X1247303Y50657D01*
X1247200Y50389D01*
Y49200D01*
G01X1246270Y52454D02*
X1245960Y52684D01*
X1245805Y52952D01*
X1245753Y53259D01*
X1245856Y53642D01*
X1246115Y53910D01*
X1246425Y53987D01*
X1246735Y53949D01*
X1246993Y53795D01*
X1247510Y53029D01*
X1247871Y52684D01*
X1248388Y52454D01*
X1248853Y52377D01*
Y53987D01*
G01X1247274Y42089D02*
X1247119Y42242D01*
X1246860Y42357D01*
X1246499Y42434D01*
X1246189Y42357D01*
X1245982Y42204D01*
X1245827Y41935D01*
Y40900D01*
X1248927D01*
Y42165D01*
X1248720Y42434D01*
X1248410Y42587D01*
X1248049Y42664D01*
X1247687Y42587D01*
X1247377Y42357D01*
X1247274Y42089D01*
Y40900D01*
G01X1248307Y44039D02*
X1248669Y44269D01*
X1248875Y44575D01*
X1248927Y44920D01*
X1248875Y45227D01*
X1248617Y45534D01*
X1248307Y45725D01*
X1247997Y45764D01*
X1247635Y45687D01*
X1247377Y45419D01*
X1247274Y45150D01*
Y44805D01*
G01Y45150D02*
X1247119Y45380D01*
X1246860Y45572D01*
X1246550Y45649D01*
X1246240Y45572D01*
X1245982Y45380D01*
X1245827Y45035D01*
X1245879Y44690D01*
X1246085Y44345D01*
G01X1247326Y59289D02*
X1247171Y59442D01*
X1246912Y59557D01*
X1246551Y59634D01*
X1246241Y59557D01*
X1246034Y59404D01*
X1245879Y59135D01*
Y58100D01*
X1248979D01*
Y59365D01*
X1248772Y59634D01*
X1248462Y59787D01*
X1248101Y59864D01*
X1247739Y59787D01*
X1247429Y59557D01*
X1247326Y59289D01*
Y58100D01*
G01X1248979Y62082D02*
X1245879D01*
X1246499Y61622D01*
G01X1248979D02*
Y62542D01*
G01X1227824Y91999D02*
X1230824D01*
G01X1235124Y95099D02*
Y88899D01*
X1231924D01*
Y95099D01*
X1235124D01*
G01X1232024Y91999D02*
X1235024D01*
G01X1246873Y104505D02*
X1240573D01*
Y106385D01*
X1240888Y107012D01*
X1241623Y107482D01*
X1242463Y107639D01*
X1243303Y107482D01*
X1243933Y107090D01*
X1244248Y106385D01*
Y104505D01*
G01X1246873Y110805D02*
X1240573D01*
Y112764D01*
X1240888Y113390D01*
X1241308Y113782D01*
X1242148Y113939D01*
X1242988Y113782D01*
X1243513Y113312D01*
X1243828Y112764D01*
Y110805D01*
G01Y112764D02*
X1246873Y113939D01*
G01Y120239D02*
Y117105D01*
X1240573D01*
Y120239D01*
G01X1243618Y118985D02*
Y117105D01*
G01X1246033Y123327D02*
X1246558Y123954D01*
X1246873Y124659D01*
Y125285D01*
X1246558Y125912D01*
X1246033Y126382D01*
X1245298Y126617D01*
X1244563Y126460D01*
X1243933Y126069D01*
X1243513Y125364D01*
X1243303Y124424D01*
X1242883Y123875D01*
X1242148Y123640D01*
X1241413Y123797D01*
X1240888Y124189D01*
X1240573Y124737D01*
Y125285D01*
X1240783Y125834D01*
X1241308Y126304D01*
G01X1246033Y129627D02*
X1246558Y130254D01*
X1246873Y130959D01*
Y131585D01*
X1246558Y132212D01*
X1246033Y132682D01*
X1245298Y132917D01*
X1244563Y132760D01*
X1243933Y132369D01*
X1243513Y131664D01*
X1243303Y130724D01*
X1242883Y130175D01*
X1242148Y129940D01*
X1241413Y130097D01*
X1240888Y130489D01*
X1240573Y131037D01*
Y131585D01*
X1240783Y132134D01*
X1241308Y132604D01*
G01X1244773Y136554D02*
Y138590D01*
G01X1246873Y142384D02*
X1240573D01*
Y145360D01*
G01X1243618Y144264D02*
Y142384D01*
G01X1240573Y149232D02*
Y151112D01*
G01Y150172D02*
X1246873D01*
G01Y149232D02*
Y151112D01*
G01X1240573Y156472D02*
X1246873D01*
G01X1240573Y154670D02*
Y158274D01*
G01X1229460Y121161D02*
X1235660D01*
Y117961D01*
X1229460D01*
Y121161D01*
G01Y115643D02*
X1235660D01*
Y112443D01*
X1229460D01*
Y115643D01*
G01Y109961D02*
X1235660D01*
Y106761D01*
X1229460D01*
Y109961D01*
G01Y104461D02*
X1235660D01*
Y101261D01*
X1229460D01*
Y104461D01*
G01X1236993Y139272D02*
Y142372D01*
X1236533Y141752D01*
G01Y139272D02*
X1237453D01*
G01X1235478Y160042D02*
Y163142D01*
X1235018Y162522D01*
G01Y160042D02*
X1235938D01*
G01X1234436Y184306D02*
X1234746Y184498D01*
X1234953Y184728D01*
X1235056Y184996D01*
X1234953Y185303D01*
X1234746Y185533D01*
X1234436Y185763D01*
X1234023Y185840D01*
X1231956D01*
G01X1235056Y188173D02*
X1231956D01*
X1232576Y187713D01*
G01X1235056D02*
Y188633D01*
G01Y191273D02*
X1235004Y191541D01*
X1234849Y191848D01*
X1234591Y192040D01*
X1234229Y192116D01*
X1233868Y192040D01*
X1233558Y191810D01*
X1233403Y191465D01*
Y191081D01*
X1233299Y190851D01*
X1233041Y190660D01*
X1232679Y190583D01*
X1232318Y190698D01*
X1232059Y190966D01*
X1231956Y191273D01*
X1232059Y191580D01*
X1232318Y191848D01*
X1232679Y191963D01*
X1233041Y191886D01*
X1233299Y191695D01*
X1233403Y191465D01*
Y191081D01*
X1233558Y190736D01*
X1233868Y190506D01*
X1234229Y190430D01*
X1234591Y190506D01*
X1234849Y190698D01*
X1235004Y191005D01*
X1235056Y191273D01*
G01X1256870Y86022D02*
Y-52954D01*
G01X1259191Y6093D02*
X1259036Y5863D01*
X1258933Y5595D01*
Y5288D01*
X1259088Y4943D01*
X1259346Y4675D01*
X1259656Y4483D01*
X1260173Y4330D01*
X1260638Y4292D01*
X1261103Y4368D01*
X1261413Y4483D01*
X1261723Y4713D01*
X1261930Y4982D01*
X1262033Y5250D01*
Y5518D01*
X1261930Y5787D01*
X1261775Y6017D01*
X1261568Y6208D01*
G01X1261413Y7507D02*
X1261775Y7737D01*
X1261981Y8043D01*
X1262033Y8388D01*
X1261981Y8695D01*
X1261723Y9002D01*
X1261413Y9193D01*
X1261103Y9232D01*
X1260741Y9155D01*
X1260483Y8887D01*
X1260380Y8618D01*
Y8273D01*
G01Y8618D02*
X1260225Y8848D01*
X1259966Y9040D01*
X1259656Y9117D01*
X1259346Y9040D01*
X1259088Y8848D01*
X1258933Y8503D01*
X1258985Y8158D01*
X1259191Y7813D01*
G01X1262033Y11450D02*
X1258933D01*
X1259553Y10990D01*
G01X1262033D02*
Y11910D01*
G01X1263091Y6093D02*
X1262936Y5863D01*
X1262833Y5595D01*
Y5288D01*
X1262988Y4943D01*
X1263246Y4675D01*
X1263556Y4483D01*
X1264073Y4330D01*
X1264538Y4292D01*
X1265003Y4368D01*
X1265313Y4483D01*
X1265623Y4713D01*
X1265830Y4982D01*
X1265933Y5250D01*
Y5518D01*
X1265830Y5787D01*
X1265675Y6017D01*
X1265468Y6208D01*
G01X1263350Y7622D02*
X1263040Y7852D01*
X1262885Y8120D01*
X1262833Y8427D01*
X1262936Y8810D01*
X1263195Y9078D01*
X1263505Y9155D01*
X1263815Y9117D01*
X1264073Y8963D01*
X1264590Y8197D01*
X1264951Y7852D01*
X1265468Y7622D01*
X1265933Y7545D01*
Y9155D01*
G01Y11450D02*
X1265881Y11718D01*
X1265726Y12025D01*
X1265468Y12217D01*
X1265106Y12293D01*
X1264745Y12217D01*
X1264435Y11987D01*
X1264280Y11642D01*
Y11258D01*
X1264176Y11028D01*
X1263918Y10837D01*
X1263556Y10760D01*
X1263195Y10875D01*
X1262936Y11143D01*
X1262833Y11450D01*
X1262936Y11757D01*
X1263195Y12025D01*
X1263556Y12140D01*
X1263918Y12063D01*
X1264176Y11872D01*
X1264280Y11642D01*
Y11258D01*
X1264435Y10913D01*
X1264745Y10683D01*
X1265106Y10607D01*
X1265468Y10683D01*
X1265726Y10875D01*
X1265881Y11182D01*
X1265933Y11450D01*
G01X1252991Y5893D02*
X1252836Y5663D01*
X1252733Y5395D01*
Y5088D01*
X1252888Y4743D01*
X1253146Y4475D01*
X1253456Y4283D01*
X1253973Y4130D01*
X1254438Y4092D01*
X1254903Y4168D01*
X1255213Y4283D01*
X1255523Y4513D01*
X1255730Y4782D01*
X1255833Y5050D01*
Y5318D01*
X1255730Y5587D01*
X1255575Y5817D01*
X1255368Y6008D01*
G01X1255213Y7307D02*
X1255575Y7537D01*
X1255781Y7843D01*
X1255833Y8188D01*
X1255781Y8495D01*
X1255523Y8802D01*
X1255213Y8993D01*
X1254903Y9032D01*
X1254541Y8955D01*
X1254283Y8687D01*
X1254180Y8418D01*
Y8073D01*
G01Y8418D02*
X1254025Y8648D01*
X1253766Y8840D01*
X1253456Y8917D01*
X1253146Y8840D01*
X1252888Y8648D01*
X1252733Y8303D01*
X1252785Y7958D01*
X1252991Y7613D01*
G01X1253250Y10522D02*
X1252940Y10752D01*
X1252785Y11020D01*
X1252733Y11327D01*
X1252836Y11710D01*
X1253095Y11978D01*
X1253405Y12055D01*
X1253715Y12017D01*
X1253973Y11863D01*
X1254490Y11097D01*
X1254851Y10752D01*
X1255368Y10522D01*
X1255833Y10445D01*
Y12055D01*
G01X1267291Y6093D02*
X1267136Y5863D01*
X1267033Y5595D01*
Y5288D01*
X1267188Y4943D01*
X1267446Y4675D01*
X1267756Y4483D01*
X1268273Y4330D01*
X1268738Y4292D01*
X1269203Y4368D01*
X1269513Y4483D01*
X1269823Y4713D01*
X1270030Y4982D01*
X1270133Y5250D01*
Y5518D01*
X1270030Y5787D01*
X1269875Y6017D01*
X1269668Y6208D01*
G01X1267550Y7622D02*
X1267240Y7852D01*
X1267085Y8120D01*
X1267033Y8427D01*
X1267136Y8810D01*
X1267395Y9078D01*
X1267705Y9155D01*
X1268015Y9117D01*
X1268273Y8963D01*
X1268790Y8197D01*
X1269151Y7852D01*
X1269668Y7622D01*
X1270133Y7545D01*
Y9155D01*
G01Y11373D02*
X1269461Y11450D01*
X1268893Y11565D01*
X1268376Y11718D01*
X1267808Y11910D01*
X1267033Y12217D01*
Y10683D01*
G01X1258735Y17013D02*
Y14791D01*
X1258888Y14326D01*
X1259195Y14016D01*
X1259578Y13913D01*
X1259961Y14016D01*
X1260268Y14326D01*
X1260421Y14791D01*
Y17013D01*
G01X1262678Y13913D02*
X1262946Y13965D01*
X1263253Y14120D01*
X1263445Y14378D01*
X1263521Y14740D01*
X1263445Y15101D01*
X1263215Y15411D01*
X1262870Y15566D01*
X1262486D01*
X1262256Y15670D01*
X1262065Y15928D01*
X1261988Y16290D01*
X1262103Y16651D01*
X1262371Y16910D01*
X1262678Y17013D01*
X1262985Y16910D01*
X1263253Y16651D01*
X1263368Y16290D01*
X1263291Y15928D01*
X1263100Y15670D01*
X1262870Y15566D01*
X1262486D01*
X1262141Y15411D01*
X1261911Y15101D01*
X1261835Y14740D01*
X1261911Y14378D01*
X1262103Y14120D01*
X1262410Y13965D01*
X1262678Y13913D01*
G01X1265823Y33446D02*
X1266831D01*
Y29509D01*
X1264423D01*
G01X1271000Y7300D02*
Y13500D01*
X1274200D01*
Y7300D01*
X1271000D01*
G01X1274100Y10400D02*
X1271100D01*
G01X1270204Y32523D02*
X1267104D01*
X1267724Y32063D01*
G01X1270204D02*
Y32983D01*
G01Y35623D02*
X1267104D01*
X1267724Y35163D01*
G01X1270204D02*
Y36083D01*
G01X1266872Y42087D02*
X1260118D01*
G01D02*
Y53154D01*
G01X1303623Y33446D02*
X1305886D01*
Y90532D01*
X1257658D01*
Y33446D01*
X1259923D01*
G01X1260118Y60154D02*
Y71221D01*
G01D02*
X1265272D01*
G01X1262823Y80696D02*
Y83796D01*
X1262363Y83176D01*
G01Y80696D02*
X1263283D01*
G01X1265923Y83796D02*
X1265616Y83693D01*
X1265386Y83434D01*
X1265233Y83124D01*
X1265118Y82711D01*
X1265080Y82246D01*
X1265118Y81781D01*
X1265233Y81368D01*
X1265386Y81058D01*
X1265616Y80799D01*
X1265923Y80696D01*
X1266230Y80799D01*
X1266460Y81058D01*
X1266613Y81368D01*
X1266728Y81781D01*
X1266766Y82246D01*
X1266728Y82711D01*
X1266613Y83124D01*
X1266460Y83434D01*
X1266230Y83693D01*
X1265923Y83796D01*
G01X1293573Y10275D02*
X1293103Y10590D01*
X1292555Y10800D01*
X1291928D01*
X1291223Y10485D01*
X1290675Y9960D01*
X1290283Y9330D01*
X1289970Y8280D01*
X1289892Y7335D01*
X1290048Y6390D01*
X1290283Y5760D01*
X1290753Y5130D01*
X1291302Y4710D01*
X1291850Y4500D01*
X1292398D01*
X1292947Y4710D01*
X1293417Y5025D01*
X1293808Y5445D01*
G01X1298150Y4500D02*
X1297523Y4605D01*
X1296975Y5025D01*
X1296505Y5655D01*
X1296192Y6390D01*
X1296035Y7230D01*
Y8070D01*
X1296192Y8910D01*
X1296505Y9645D01*
X1296975Y10275D01*
X1297523Y10695D01*
X1298150Y10800D01*
X1298777Y10695D01*
X1299325Y10275D01*
X1299795Y9645D01*
X1300108Y8910D01*
X1300265Y8070D01*
Y7230D01*
X1300108Y6390D01*
X1299795Y5655D01*
X1299325Y5025D01*
X1298777Y4605D01*
X1298150Y4500D01*
G01X1302648D02*
Y10800D01*
X1306252Y4500D01*
Y10800D01*
G01X1308948Y4500D02*
Y10800D01*
X1312552Y4500D01*
Y10800D01*
G01X1317990Y4500D02*
Y10800D01*
X1315092Y6285D01*
X1319008D01*
G01X1296621Y24095D02*
X1296311Y24325D01*
X1296156Y24593D01*
X1296104Y24900D01*
X1296207Y25283D01*
X1296466Y25551D01*
X1296776Y25628D01*
X1297086Y25590D01*
X1297344Y25436D01*
X1297861Y24670D01*
X1298222Y24325D01*
X1298739Y24095D01*
X1299204Y24018D01*
Y25628D01*
G01X1296104Y27923D02*
X1296207Y27616D01*
X1296466Y27386D01*
X1296776Y27233D01*
X1297189Y27118D01*
X1297654Y27080D01*
X1298119Y27118D01*
X1298532Y27233D01*
X1298842Y27386D01*
X1299101Y27616D01*
X1299204Y27923D01*
X1299101Y28230D01*
X1298842Y28460D01*
X1298532Y28613D01*
X1298119Y28728D01*
X1297654Y28766D01*
X1297189Y28728D01*
X1296776Y28613D01*
X1296466Y28460D01*
X1296207Y28230D01*
X1296104Y27923D01*
G01X1299123Y29509D02*
X1296713D01*
Y33446D01*
X1297723D01*
G01X1280000Y7300D02*
Y13500D01*
X1283200D01*
Y7300D01*
X1280000D01*
G01X1283100Y10400D02*
X1280100D01*
G01X1275400Y7300D02*
Y13500D01*
X1278600D01*
Y7300D01*
X1275400D01*
G01X1278500Y10400D02*
X1275500D01*
G01X1284400Y7300D02*
Y13500D01*
X1287600D01*
Y7300D01*
X1284400D01*
G01X1287500Y10400D02*
X1284500D01*
G01X1296672Y71221D02*
X1303426D01*
G01X1298405Y15740D02*
X1299032Y15215D01*
X1299737Y14900D01*
X1300363D01*
X1300990Y15215D01*
X1301460Y15740D01*
X1301695Y16475D01*
X1301538Y17210D01*
X1301147Y17840D01*
X1300442Y18260D01*
X1299502Y18470D01*
X1298953Y18890D01*
X1298718Y19625D01*
X1298875Y20360D01*
X1299267Y20885D01*
X1299815Y21200D01*
X1300363D01*
X1300912Y20990D01*
X1301382Y20465D01*
G01X1304862Y14900D02*
Y21200D01*
X1307838D01*
G01X1306742Y18155D02*
X1304862D01*
G01X1311083Y14900D02*
Y21200D01*
X1312963D01*
X1313590Y20885D01*
X1314060Y20150D01*
X1314217Y19310D01*
X1314060Y18470D01*
X1313668Y17840D01*
X1312963Y17525D01*
X1311083D01*
G01X1318088Y17000D02*
X1319968D01*
G01X1318950Y18365D02*
Y15635D01*
G01X1313760Y223603D02*
Y29509D01*
X1302123D01*
G01X1303426Y42087D02*
X1298272D01*
G01X1303426D02*
Y54154D01*
G01Y59154D02*
Y71221D01*
G01X1298297Y78596D02*
Y81696D01*
X1297837Y81076D01*
G01Y78596D02*
X1298757D01*
G01X1315946Y111863D02*
X1315791Y112016D01*
X1315532Y112131D01*
X1315171Y112208D01*
X1314861Y112131D01*
X1314654Y111978D01*
X1314499Y111709D01*
Y110674D01*
X1317599D01*
Y111939D01*
X1317392Y112208D01*
X1317082Y112361D01*
X1316721Y112438D01*
X1316359Y112361D01*
X1316049Y112131D01*
X1315946Y111863D01*
Y110674D01*
G01X1317599Y114656D02*
X1314499D01*
X1315119Y114196D01*
G01X1317599D02*
Y115116D01*
G01X1315846Y121863D02*
X1315691Y122016D01*
X1315432Y122131D01*
X1315071Y122208D01*
X1314761Y122131D01*
X1314554Y121978D01*
X1314399Y121709D01*
Y120674D01*
X1317499D01*
Y121939D01*
X1317292Y122208D01*
X1316982Y122361D01*
X1316621Y122438D01*
X1316259Y122361D01*
X1315949Y122131D01*
X1315846Y121863D01*
Y120674D01*
G01X1314916Y123928D02*
X1314606Y124158D01*
X1314451Y124426D01*
X1314399Y124733D01*
X1314502Y125116D01*
X1314761Y125384D01*
X1315071Y125461D01*
X1315381Y125423D01*
X1315639Y125269D01*
X1316156Y124503D01*
X1316517Y124158D01*
X1317034Y123928D01*
X1317499Y123851D01*
Y125461D01*
G01X1318426Y126150D02*
Y107162D01*
X1394450D01*
X1394452Y110814D01*
G01X1317584Y137498D02*
X1314484Y138456D01*
X1317584Y139414D01*
G01X1316499Y139069D02*
Y137843D01*
G01X1317584Y141556D02*
X1317532Y141824D01*
X1317377Y142131D01*
X1317119Y142323D01*
X1316757Y142399D01*
X1316396Y142323D01*
X1316086Y142093D01*
X1315931Y141748D01*
Y141364D01*
X1315827Y141134D01*
X1315569Y140943D01*
X1315207Y140866D01*
X1314846Y140981D01*
X1314587Y141249D01*
X1314484Y141556D01*
X1314587Y141863D01*
X1314846Y142131D01*
X1315207Y142246D01*
X1315569Y142169D01*
X1315827Y141978D01*
X1315931Y141748D01*
Y141364D01*
X1316086Y141019D01*
X1316396Y140789D01*
X1316757Y140713D01*
X1317119Y140789D01*
X1317377Y140981D01*
X1317532Y141288D01*
X1317584Y141556D01*
G01X1318426Y188350D02*
Y137350D01*
G01X1317584Y150198D02*
X1314484Y151156D01*
X1317584Y152114D01*
G01X1316499Y151769D02*
Y150543D01*
G01X1317584Y154179D02*
X1316912Y154256D01*
X1316344Y154371D01*
X1315827Y154524D01*
X1315259Y154716D01*
X1314484Y155023D01*
Y153489D01*
G01X1394450Y200150D02*
Y219170D01*
X1318426D01*
Y201050D01*
G01X1320985Y-49508D02*
X1391851D01*
Y80611D01*
X1320985D01*
Y35300D01*
G01Y18000D02*
Y-49508D01*
G01X1380040Y68800D02*
X1332796D01*
Y-37697D01*
X1380040D01*
Y68800D01*
G01X1332163Y3356D02*
X1325863D01*
Y5236D01*
X1326178Y5863D01*
X1326913Y6333D01*
X1327753Y6490D01*
X1328593Y6333D01*
X1329223Y5941D01*
X1329538Y5236D01*
Y3356D01*
G01X1332163Y9656D02*
X1325863D01*
Y11615D01*
X1326178Y12241D01*
X1326598Y12633D01*
X1327438Y12790D01*
X1328278Y12633D01*
X1328803Y12163D01*
X1329118Y11615D01*
Y9656D01*
G01Y11615D02*
X1332163Y12790D01*
G01Y19090D02*
Y15956D01*
X1325863D01*
Y19090D01*
G01X1328908Y17836D02*
Y15956D01*
G01X1331323Y22178D02*
X1331848Y22805D01*
X1332163Y23510D01*
Y24136D01*
X1331848Y24763D01*
X1331323Y25233D01*
X1330588Y25468D01*
X1329853Y25311D01*
X1329223Y24920D01*
X1328803Y24215D01*
X1328593Y23275D01*
X1328173Y22726D01*
X1327438Y22491D01*
X1326703Y22648D01*
X1326178Y23040D01*
X1325863Y23588D01*
Y24136D01*
X1326073Y24685D01*
X1326598Y25155D01*
G01X1331323Y28478D02*
X1331848Y29105D01*
X1332163Y29810D01*
Y30436D01*
X1331848Y31063D01*
X1331323Y31533D01*
X1330588Y31768D01*
X1329853Y31611D01*
X1329223Y31220D01*
X1328803Y30515D01*
X1328593Y29575D01*
X1328173Y29026D01*
X1327438Y28791D01*
X1326703Y28948D01*
X1326178Y29340D01*
X1325863Y29888D01*
Y30436D01*
X1326073Y30985D01*
X1326598Y31455D01*
G01X1330063Y35405D02*
Y37441D01*
G01X1332163Y41235D02*
X1325863D01*
Y44211D01*
G01X1328908Y43115D02*
Y41235D01*
G01X1325863Y48083D02*
Y49963D01*
G01Y49023D02*
X1332163D01*
G01Y48083D02*
Y49963D01*
G01X1325863Y55323D02*
X1332163D01*
G01X1325863Y53521D02*
Y57125D01*
G01X1335439Y71682D02*
X1335707Y72043D01*
X1335937Y72250D01*
X1336244Y72353D01*
X1336512Y72250D01*
X1336704Y72043D01*
X1336857Y71733D01*
X1336895Y71372D01*
X1336857Y71062D01*
X1336704Y70752D01*
X1336474Y70493D01*
X1336205Y70390D01*
X1335899Y70493D01*
X1335630Y70803D01*
X1335477Y71268D01*
X1335439Y71785D01*
X1335515Y72457D01*
X1335630Y72818D01*
X1335822Y73180D01*
X1336090Y73438D01*
X1336359Y73490D01*
X1336627Y73387D01*
X1336819Y73128D01*
G01X1341583Y100500D02*
Y94200D01*
X1344717D01*
G01X1347492D02*
X1349450Y100500D01*
X1351408Y94200D01*
G01X1350703Y96405D02*
X1348197D01*
G01X1353948Y94200D02*
Y100500D01*
X1357552Y94200D01*
Y100500D01*
G01X1360327Y95460D02*
X1360797Y94725D01*
X1361423Y94305D01*
X1362128Y94200D01*
X1362755Y94305D01*
X1363382Y94830D01*
X1363773Y95460D01*
X1363852Y96090D01*
X1363695Y96825D01*
X1363147Y97350D01*
X1362598Y97560D01*
X1361893D01*
G01X1362598D02*
X1363068Y97875D01*
X1363460Y98400D01*
X1363617Y99030D01*
X1363460Y99660D01*
X1363068Y100185D01*
X1362363Y100500D01*
X1361658Y100395D01*
X1360953Y99975D01*
G01X1366000Y96300D02*
X1366783Y98400D01*
X1367567D01*
X1369133Y94200D01*
X1369917D01*
X1370700Y96300D01*
G01X1375590Y94200D02*
Y100500D01*
X1372692Y95985D01*
X1376608D01*
G01X1335300Y81400D02*
X1331500D01*
Y82900D01*
X1326800D01*
Y104400D01*
X1340400D01*
Y92800D01*
X1378000D01*
Y106400D01*
X1378900D01*
G01X1328112Y87439D02*
X1334312D01*
Y84239D01*
X1328112D01*
Y87439D01*
G01Y91939D02*
X1334312D01*
Y88739D01*
X1328112D01*
Y91939D01*
G01Y96239D02*
X1334312D01*
Y93039D01*
X1328112D01*
Y96239D01*
G01X1328212Y100839D02*
X1334412D01*
Y97639D01*
X1328212D01*
Y100839D01*
G01X1342712Y81658D02*
X1336512D01*
Y84858D01*
X1342712D01*
Y81658D01*
G01Y85958D02*
X1336512D01*
Y89158D01*
X1342712D01*
Y85958D01*
G01X1352427Y70590D02*
Y73690D01*
X1351009Y71468D01*
X1352925D01*
G01X1343324Y70655D02*
X1343554Y70397D01*
X1343822Y70242D01*
X1344167Y70190D01*
X1344512Y70293D01*
X1344780Y70500D01*
X1344972Y70862D01*
X1345010Y71275D01*
X1344934Y71688D01*
X1344742Y71947D01*
X1344474Y72153D01*
X1344205Y72205D01*
X1343937Y72153D01*
X1343592Y71947D01*
X1343707Y73290D01*
X1344742D01*
G01X1359724Y70810D02*
X1359954Y70448D01*
X1360260Y70242D01*
X1360605Y70190D01*
X1360912Y70242D01*
X1361219Y70500D01*
X1361410Y70810D01*
X1361449Y71120D01*
X1361372Y71482D01*
X1361104Y71740D01*
X1360835Y71843D01*
X1360490D01*
G01X1360835D02*
X1361065Y71998D01*
X1361257Y72257D01*
X1361334Y72567D01*
X1361257Y72877D01*
X1361065Y73135D01*
X1360720Y73290D01*
X1360375Y73238D01*
X1360030Y73032D01*
G01X1343700Y81400D02*
X1374000D01*
G01X1348657Y82660D02*
Y88860D01*
X1351857D01*
Y82660D01*
X1348657D01*
G01X1357242Y88433D02*
Y82233D01*
X1354042D01*
Y88433D01*
X1357242D01*
G01X1358342Y82233D02*
Y88433D01*
X1361542D01*
Y82233D01*
X1358342D01*
G01X1362658Y82167D02*
Y88367D01*
X1365858D01*
Y82167D01*
X1362658D01*
G01X1343958Y82688D02*
Y88888D01*
X1347158D01*
Y82688D01*
X1343958D01*
G01X1352445Y103337D02*
X1352637Y103027D01*
X1352867Y102820D01*
X1353135Y102717D01*
X1353442Y102820D01*
X1353672Y103027D01*
X1353902Y103337D01*
X1353979Y103750D01*
Y105817D01*
G01X1355584Y105300D02*
X1355814Y105610D01*
X1356082Y105765D01*
X1356389Y105817D01*
X1356772Y105714D01*
X1357040Y105455D01*
X1357117Y105145D01*
X1357079Y104835D01*
X1356925Y104577D01*
X1356159Y104060D01*
X1355814Y103699D01*
X1355584Y103182D01*
X1355507Y102717D01*
X1357117D01*
G01X1358569Y103337D02*
X1358799Y102975D01*
X1359105Y102769D01*
X1359450Y102717D01*
X1359757Y102769D01*
X1360064Y103027D01*
X1360255Y103337D01*
X1360294Y103647D01*
X1360217Y104009D01*
X1359949Y104267D01*
X1359680Y104370D01*
X1359335D01*
G01X1359680D02*
X1359910Y104525D01*
X1360102Y104784D01*
X1360179Y105094D01*
X1360102Y105404D01*
X1359910Y105662D01*
X1359565Y105817D01*
X1359220Y105765D01*
X1358875Y105559D01*
G01X1381909Y3499D02*
X1382867Y6599D01*
X1383825Y3499D01*
G01X1383480Y4584D02*
X1382254D01*
G01X1393500Y17698D02*
X1387264D01*
G01D02*
Y235414D01*
X1474862D01*
Y17698D01*
X1423700D01*
G01X1383847Y20213D02*
X1383617Y20368D01*
X1383349Y20471D01*
X1383042D01*
X1382697Y20316D01*
X1382429Y20058D01*
X1382237Y19748D01*
X1382084Y19231D01*
X1382046Y18766D01*
X1382122Y18301D01*
X1382237Y17991D01*
X1382467Y17681D01*
X1382736Y17474D01*
X1383004Y17371D01*
X1383272D01*
X1383541Y17474D01*
X1383771Y17629D01*
X1383962Y17836D01*
G01X1383711Y13636D02*
X1383864Y13791D01*
X1383979Y14050D01*
X1384056Y14411D01*
X1383979Y14721D01*
X1383826Y14928D01*
X1383557Y15083D01*
X1382522D01*
Y11983D01*
X1383787D01*
X1384056Y12190D01*
X1384209Y12500D01*
X1384286Y12861D01*
X1384209Y13223D01*
X1383979Y13533D01*
X1383711Y13636D01*
X1382522D01*
G01X1383871Y28647D02*
X1382337D01*
Y31747D01*
X1383871D01*
G01X1383257Y30249D02*
X1382337D01*
G01X1382461Y23059D02*
Y26159D01*
X1383227D01*
X1383534Y26004D01*
X1383764Y25797D01*
X1383956Y25487D01*
X1384109Y25126D01*
X1384147Y24609D01*
X1384109Y24092D01*
X1383956Y23731D01*
X1383764Y23421D01*
X1383534Y23214D01*
X1383227Y23059D01*
X1382461D01*
G01X1381976Y34135D02*
Y37235D01*
X1383432D01*
G01X1382896Y35737D02*
X1381976D01*
G01X1383234Y41373D02*
X1384001D01*
Y40443D01*
X1383771Y40133D01*
X1383502Y39926D01*
X1383119Y39823D01*
X1382736Y39926D01*
X1382467Y40133D01*
X1382237Y40443D01*
X1382084Y40805D01*
X1382007Y41218D01*
Y41580D01*
X1382084Y41890D01*
X1382237Y42251D01*
X1382467Y42561D01*
X1382697Y42768D01*
X1383004Y42923D01*
X1383272D01*
X1383579Y42820D01*
X1383809Y42613D01*
G01X1383401Y48288D02*
Y45188D01*
G01X1381791D02*
Y48288D01*
G01Y46738D02*
X1383401D01*
G01X1383056Y50700D02*
X1382136D01*
G01X1382596D02*
Y53800D01*
G01X1383056D02*
X1382136D01*
G01X1368139Y72973D02*
X1368369Y73283D01*
X1368637Y73438D01*
X1368944Y73490D01*
X1369327Y73387D01*
X1369595Y73128D01*
X1369672Y72818D01*
X1369634Y72508D01*
X1369480Y72250D01*
X1368714Y71733D01*
X1368369Y71372D01*
X1368139Y70855D01*
X1368062Y70390D01*
X1369672D01*
G01X1376567Y70490D02*
Y73590D01*
X1376107Y72970D01*
G01Y70490D02*
X1377027D01*
G01X1373557Y90353D02*
X1373710Y90508D01*
X1373825Y90767D01*
X1373902Y91128D01*
X1373825Y91438D01*
X1373672Y91645D01*
X1373403Y91800D01*
X1372368D01*
Y88700D01*
X1373633D01*
X1373902Y88907D01*
X1374055Y89217D01*
X1374132Y89578D01*
X1374055Y89940D01*
X1373825Y90250D01*
X1373557Y90353D01*
X1372368D01*
G01X1386300Y81600D02*
X1386500D01*
Y106500D01*
X1386300D01*
G01X1385812Y94261D02*
X1379612D01*
Y97461D01*
X1385812D01*
Y94261D01*
G01X1385688Y89961D02*
X1379488D01*
Y93161D01*
X1385688D01*
Y89961D01*
G01X1370258Y88367D02*
Y82167D01*
X1367058D01*
Y88367D01*
X1370258D01*
G01X1374758Y81788D02*
Y87988D01*
X1377958D01*
Y81788D01*
X1374758D01*
G01X1379488Y84642D02*
X1385688D01*
Y81442D01*
X1379488D01*
Y84642D01*
G01Y88842D02*
X1385688D01*
Y85642D01*
X1379488D01*
Y88842D01*
G01X1385812Y98561D02*
X1379612D01*
Y101761D01*
X1385812D01*
Y98561D01*
G01Y102861D02*
X1379612D01*
Y106061D01*
X1385812D01*
Y102861D01*
G01X1400993Y7083D02*
X1400613Y7333D01*
X1400170Y7500D01*
X1399663D01*
X1399093Y7250D01*
X1398650Y6833D01*
X1398333Y6333D01*
X1398080Y5500D01*
X1398017Y4750D01*
X1398143Y4000D01*
X1398333Y3500D01*
X1398713Y3000D01*
X1399157Y2667D01*
X1399600Y2500D01*
X1400043D01*
X1400487Y2667D01*
X1400867Y2917D01*
X1401183Y3250D01*
G01X1404700Y2500D02*
X1404193Y2583D01*
X1403750Y2917D01*
X1403370Y3417D01*
X1403117Y4000D01*
X1402990Y4667D01*
Y5333D01*
X1403117Y6000D01*
X1403370Y6583D01*
X1403750Y7083D01*
X1404193Y7417D01*
X1404700Y7500D01*
X1405207Y7417D01*
X1405650Y7083D01*
X1406030Y6583D01*
X1406283Y6000D01*
X1406410Y5333D01*
Y4667D01*
X1406283Y4000D01*
X1406030Y3417D01*
X1405650Y2917D01*
X1405207Y2583D01*
X1404700Y2500D01*
G01X1408343D02*
Y7500D01*
X1411257Y2500D01*
Y7500D01*
G01X1413443Y2500D02*
Y7500D01*
X1416357Y2500D01*
Y7500D01*
G01X1418607Y3500D02*
X1418987Y2917D01*
X1419493Y2583D01*
X1420063Y2500D01*
X1420570Y2583D01*
X1421077Y3000D01*
X1421393Y3500D01*
X1421457Y4000D01*
X1421330Y4583D01*
X1420887Y5000D01*
X1420443Y5167D01*
X1419873D01*
G01X1420443D02*
X1420823Y5417D01*
X1421140Y5833D01*
X1421267Y6333D01*
X1421140Y6833D01*
X1420823Y7250D01*
X1420253Y7500D01*
X1419683Y7417D01*
X1419113Y7083D01*
G01X1395881Y5780D02*
X1396191Y5972D01*
X1396398Y6202D01*
X1396501Y6470D01*
X1396398Y6777D01*
X1396191Y7007D01*
X1395881Y7237D01*
X1395468Y7314D01*
X1393401D01*
G01X1396501Y9570D02*
X1395829Y9647D01*
X1395261Y9762D01*
X1394744Y9915D01*
X1394176Y10107D01*
X1393401Y10414D01*
Y8880D01*
G01X1403170Y9467D02*
X1403677Y9050D01*
X1404247Y8800D01*
X1404753D01*
X1405260Y9050D01*
X1405640Y9467D01*
X1405830Y10050D01*
X1405703Y10633D01*
X1405387Y11133D01*
X1404817Y11467D01*
X1404057Y11633D01*
X1403613Y11967D01*
X1403423Y12550D01*
X1403550Y13133D01*
X1403867Y13550D01*
X1404310Y13800D01*
X1404753D01*
X1405197Y13633D01*
X1405577Y13217D01*
G01X1408397Y8800D02*
Y13800D01*
X1410803D01*
G01X1409917Y11383D02*
X1408397D01*
G01X1413433Y8800D02*
Y13800D01*
X1414953D01*
X1415460Y13550D01*
X1415840Y12967D01*
X1415967Y12300D01*
X1415840Y11633D01*
X1415523Y11133D01*
X1414953Y10883D01*
X1413433D01*
G01X1419103Y10467D02*
X1420623D01*
G01X1419800Y11550D02*
Y9383D01*
G01X1397583Y21200D02*
Y14900D01*
X1400717D01*
G01X1403492D02*
X1405450Y21200D01*
X1407408Y14900D01*
G01X1406703Y17105D02*
X1404197D01*
G01X1409948Y14900D02*
Y21200D01*
X1413552Y14900D01*
Y21200D01*
G01X1397192Y22100D02*
X1399150Y28400D01*
X1401108Y22100D01*
G01X1400403Y24305D02*
X1397897D01*
G01X1404510Y28400D02*
X1406390D01*
G01X1405450D02*
Y22100D01*
G01X1404510D02*
X1406390D01*
G01X1410183D02*
Y28400D01*
X1412142D01*
X1412768Y28085D01*
X1413160Y27665D01*
X1413317Y26825D01*
X1413160Y25985D01*
X1412690Y25460D01*
X1412142Y25145D01*
X1410183D01*
G01X1412142D02*
X1413317Y22100D01*
G01X1416013D02*
Y28400D01*
X1418050Y23150D01*
X1420087Y28400D01*
Y22100D01*
G01X1422392D02*
X1424350Y28400D01*
X1426308Y22100D01*
G01X1425603Y24305D02*
X1423097D01*
G01X1429005Y22100D02*
X1432295Y28400D01*
G01X1429005D02*
X1432295Y22100D01*
G01X1410614Y29509D02*
X1399075D01*
Y223603D01*
X1463051D01*
G01X1416164Y42086D02*
X1409410D01*
G01D02*
Y53153D01*
G01X1452914Y33446D02*
X1455177D01*
Y90532D01*
X1406949D01*
Y33446D01*
X1409214D01*
G01X1409410Y60153D02*
Y71220D01*
G01D02*
X1414564D01*
G01X1396730Y106719D02*
X1396575Y106872D01*
X1396316Y106987D01*
X1395955Y107064D01*
X1395645Y106987D01*
X1395438Y106834D01*
X1395283Y106565D01*
Y105530D01*
X1398383D01*
Y106795D01*
X1398176Y107064D01*
X1397866Y107217D01*
X1397505Y107294D01*
X1397143Y107217D01*
X1396833Y106987D01*
X1396730Y106719D01*
Y105530D01*
G01X1398383Y109435D02*
X1397711Y109512D01*
X1397143Y109627D01*
X1396626Y109780D01*
X1396058Y109972D01*
X1395283Y110279D01*
Y108745D01*
G01X1394457Y120427D02*
X1394484Y173870D01*
X1394450Y176650D01*
G01X1398283Y137954D02*
X1395183Y138912D01*
X1398283Y139870D01*
G01X1397198Y139525D02*
Y138299D01*
G01X1395700Y141284D02*
X1395390Y141514D01*
X1395235Y141782D01*
X1395183Y142089D01*
X1395286Y142472D01*
X1395545Y142740D01*
X1395855Y142817D01*
X1396165Y142779D01*
X1396423Y142625D01*
X1396940Y141859D01*
X1397301Y141514D01*
X1397818Y141284D01*
X1398283Y141207D01*
Y142817D01*
G01X1396830Y124719D02*
X1396675Y124872D01*
X1396416Y124987D01*
X1396055Y125064D01*
X1395745Y124987D01*
X1395538Y124834D01*
X1395383Y124565D01*
Y123530D01*
X1398483D01*
Y124795D01*
X1398276Y125064D01*
X1397966Y125217D01*
X1397605Y125294D01*
X1397243Y125217D01*
X1396933Y124987D01*
X1396830Y124719D01*
Y123530D01*
G01X1398483Y127512D02*
X1398431Y127780D01*
X1398276Y128087D01*
X1398018Y128279D01*
X1397656Y128355D01*
X1397295Y128279D01*
X1396985Y128049D01*
X1396830Y127704D01*
Y127320D01*
X1396726Y127090D01*
X1396468Y126899D01*
X1396106Y126822D01*
X1395745Y126937D01*
X1395486Y127205D01*
X1395383Y127512D01*
X1395486Y127819D01*
X1395745Y128087D01*
X1396106Y128202D01*
X1396468Y128125D01*
X1396726Y127934D01*
X1396830Y127704D01*
Y127320D01*
X1396985Y126975D01*
X1397295Y126745D01*
X1397656Y126669D01*
X1398018Y126745D01*
X1398276Y126937D01*
X1398431Y127244D01*
X1398483Y127512D01*
G01X1397983Y154054D02*
X1394883Y155012D01*
X1397983Y155970D01*
G01X1396898Y155625D02*
Y154399D01*
G01X1397983Y158112D02*
X1394883D01*
X1395503Y157652D01*
G01X1397983D02*
Y158572D01*
G01X1394450Y176650D02*
Y189050D01*
G01X1423991Y5193D02*
X1423836Y4963D01*
X1423733Y4695D01*
Y4388D01*
X1423888Y4043D01*
X1424146Y3775D01*
X1424456Y3583D01*
X1424973Y3430D01*
X1425438Y3392D01*
X1425903Y3468D01*
X1426213Y3583D01*
X1426523Y3813D01*
X1426730Y4082D01*
X1426833Y4350D01*
Y4618D01*
X1426730Y4887D01*
X1426575Y5117D01*
X1426368Y5308D01*
G01X1424250Y6722D02*
X1423940Y6952D01*
X1423785Y7220D01*
X1423733Y7527D01*
X1423836Y7910D01*
X1424095Y8178D01*
X1424405Y8255D01*
X1424715Y8217D01*
X1424973Y8063D01*
X1425490Y7297D01*
X1425851Y6952D01*
X1426368Y6722D01*
X1426833Y6645D01*
Y8255D01*
G01X1426471Y9898D02*
X1426730Y10167D01*
X1426833Y10473D01*
X1426730Y10780D01*
X1426420Y11048D01*
X1425955Y11240D01*
X1425490Y11317D01*
X1424921D01*
X1424456Y11240D01*
X1424043Y11048D01*
X1423836Y10818D01*
X1423733Y10550D01*
X1423836Y10243D01*
X1424043Y10013D01*
X1424353Y9860D01*
X1424766Y9783D01*
X1425128Y9860D01*
X1425490Y10052D01*
X1425696Y10282D01*
X1425748Y10550D01*
X1425645Y10857D01*
X1425386Y11087D01*
X1424921Y11317D01*
G01X1427891Y5093D02*
X1427736Y4863D01*
X1427633Y4595D01*
Y4288D01*
X1427788Y3943D01*
X1428046Y3675D01*
X1428356Y3483D01*
X1428873Y3330D01*
X1429338Y3292D01*
X1429803Y3368D01*
X1430113Y3483D01*
X1430423Y3713D01*
X1430630Y3982D01*
X1430733Y4250D01*
Y4518D01*
X1430630Y4787D01*
X1430475Y5017D01*
X1430268Y5208D01*
G01X1430113Y6507D02*
X1430475Y6737D01*
X1430681Y7043D01*
X1430733Y7388D01*
X1430681Y7695D01*
X1430423Y8002D01*
X1430113Y8193D01*
X1429803Y8232D01*
X1429441Y8155D01*
X1429183Y7887D01*
X1429080Y7618D01*
Y7273D01*
G01Y7618D02*
X1428925Y7848D01*
X1428666Y8040D01*
X1428356Y8117D01*
X1428046Y8040D01*
X1427788Y7848D01*
X1427633Y7503D01*
X1427685Y7158D01*
X1427891Y6813D01*
G01X1427633Y10450D02*
X1427736Y10143D01*
X1427995Y9913D01*
X1428305Y9760D01*
X1428718Y9645D01*
X1429183Y9607D01*
X1429648Y9645D01*
X1430061Y9760D01*
X1430371Y9913D01*
X1430630Y10143D01*
X1430733Y10450D01*
X1430630Y10757D01*
X1430371Y10987D01*
X1430061Y11140D01*
X1429648Y11255D01*
X1429183Y11293D01*
X1428718Y11255D01*
X1428305Y11140D01*
X1427995Y10987D01*
X1427736Y10757D01*
X1427633Y10450D01*
G01X1415114Y33446D02*
X1416122D01*
Y29509D01*
X1413714D01*
G01X1431800Y9100D02*
Y15300D01*
X1435000D01*
Y9100D01*
X1431800D01*
G01X1434900Y12200D02*
X1431900D01*
G01X1419803Y32731D02*
X1416703D01*
X1417323Y32271D01*
G01X1419803D02*
Y33191D01*
G01Y35831D02*
X1416703D01*
X1417323Y35371D01*
G01X1419803D02*
Y36291D01*
G01X1413731Y79997D02*
Y83097D01*
X1413271Y82477D01*
G01Y79997D02*
X1414191D01*
G01X1416831Y83097D02*
X1416524Y82994D01*
X1416294Y82735D01*
X1416141Y82425D01*
X1416026Y82012D01*
X1415988Y81547D01*
X1416026Y81082D01*
X1416141Y80669D01*
X1416294Y80359D01*
X1416524Y80100D01*
X1416831Y79997D01*
X1417138Y80100D01*
X1417368Y80359D01*
X1417521Y80669D01*
X1417636Y81082D01*
X1417674Y81547D01*
X1417636Y82012D01*
X1417521Y82425D01*
X1417368Y82735D01*
X1417138Y82994D01*
X1416831Y83097D01*
G01X1454191Y5093D02*
X1454036Y4863D01*
X1453933Y4595D01*
Y4288D01*
X1454088Y3943D01*
X1454346Y3675D01*
X1454656Y3483D01*
X1455173Y3330D01*
X1455638Y3292D01*
X1456103Y3368D01*
X1456413Y3483D01*
X1456723Y3713D01*
X1456930Y3982D01*
X1457033Y4250D01*
Y4518D01*
X1456930Y4787D01*
X1456775Y5017D01*
X1456568Y5208D01*
G01X1454450Y6622D02*
X1454140Y6852D01*
X1453985Y7120D01*
X1453933Y7427D01*
X1454036Y7810D01*
X1454295Y8078D01*
X1454605Y8155D01*
X1454915Y8117D01*
X1455173Y7963D01*
X1455690Y7197D01*
X1456051Y6852D01*
X1456568Y6622D01*
X1457033Y6545D01*
Y8155D01*
G01X1455741Y9722D02*
X1455380Y9990D01*
X1455173Y10220D01*
X1455070Y10527D01*
X1455173Y10795D01*
X1455380Y10987D01*
X1455690Y11140D01*
X1456051Y11178D01*
X1456361Y11140D01*
X1456671Y10987D01*
X1456930Y10757D01*
X1457033Y10488D01*
X1456930Y10182D01*
X1456620Y9913D01*
X1456155Y9760D01*
X1455638Y9722D01*
X1454966Y9798D01*
X1454605Y9913D01*
X1454243Y10105D01*
X1453985Y10373D01*
X1453933Y10642D01*
X1454036Y10910D01*
X1454295Y11102D01*
G01X1450091Y4993D02*
X1449936Y4763D01*
X1449833Y4495D01*
Y4188D01*
X1449988Y3843D01*
X1450246Y3575D01*
X1450556Y3383D01*
X1451073Y3230D01*
X1451538Y3192D01*
X1452003Y3268D01*
X1452313Y3383D01*
X1452623Y3613D01*
X1452830Y3882D01*
X1452933Y4150D01*
Y4418D01*
X1452830Y4687D01*
X1452675Y4917D01*
X1452468Y5108D01*
G01X1450350Y6522D02*
X1450040Y6752D01*
X1449885Y7020D01*
X1449833Y7327D01*
X1449936Y7710D01*
X1450195Y7978D01*
X1450505Y8055D01*
X1450815Y8017D01*
X1451073Y7863D01*
X1451590Y7097D01*
X1451951Y6752D01*
X1452468Y6522D01*
X1452933Y6445D01*
Y8055D01*
G01X1452468Y9507D02*
X1452726Y9737D01*
X1452881Y10005D01*
X1452933Y10350D01*
X1452830Y10695D01*
X1452623Y10963D01*
X1452261Y11155D01*
X1451848Y11193D01*
X1451435Y11117D01*
X1451176Y10925D01*
X1450970Y10657D01*
X1450918Y10388D01*
X1450970Y10120D01*
X1451176Y9775D01*
X1449833Y9890D01*
Y10925D01*
G01X1453843Y16714D02*
Y14492D01*
X1453996Y14027D01*
X1454303Y13717D01*
X1454686Y13614D01*
X1455069Y13717D01*
X1455376Y14027D01*
X1455529Y14492D01*
Y16714D01*
G01X1457709Y13614D02*
X1457786Y14286D01*
X1457901Y14854D01*
X1458054Y15371D01*
X1458246Y15939D01*
X1458553Y16714D01*
X1457019D01*
G01X1447588Y23441D02*
X1447278Y23671D01*
X1447123Y23939D01*
X1447071Y24246D01*
X1447174Y24629D01*
X1447433Y24897D01*
X1447743Y24974D01*
X1448053Y24936D01*
X1448311Y24782D01*
X1448828Y24016D01*
X1449189Y23671D01*
X1449706Y23441D01*
X1450171Y23364D01*
Y24974D01*
G01X1447071Y27269D02*
X1447174Y26962D01*
X1447433Y26732D01*
X1447743Y26579D01*
X1448156Y26464D01*
X1448621Y26426D01*
X1449086Y26464D01*
X1449499Y26579D01*
X1449809Y26732D01*
X1450068Y26962D01*
X1450171Y27269D01*
X1450068Y27576D01*
X1449809Y27806D01*
X1449499Y27959D01*
X1449086Y28074D01*
X1448621Y28112D01*
X1448156Y28074D01*
X1447743Y27959D01*
X1447433Y27806D01*
X1447174Y27576D01*
X1447071Y27269D01*
G01X1463051Y223603D02*
Y29509D01*
X1451414D01*
G01X1448414D02*
X1446004D01*
Y33446D01*
X1447014D01*
G01X1445400Y9200D02*
Y15400D01*
X1448600D01*
Y9200D01*
X1445400D01*
G01X1448500Y12300D02*
X1445500D01*
G01X1436300Y9100D02*
Y15300D01*
X1439500D01*
Y9100D01*
X1436300D01*
G01X1439400Y12200D02*
X1436400D01*
G01X1441000Y9200D02*
Y15400D01*
X1444200D01*
Y9200D01*
X1441000D01*
G01X1444100Y12300D02*
X1441100D01*
G01X1452718Y42086D02*
X1447564D01*
G01X1452718D02*
Y54153D01*
G01X1445964Y71220D02*
X1452718D01*
G01Y59153D02*
Y71220D01*
G01X1447005Y78497D02*
Y81597D01*
X1446545Y80977D01*
G01Y78497D02*
X1447465D01*
G01X1461161Y41850D02*
Y-127559D01*
X1503091D01*
Y83189D01*
X1461161D01*
Y41850D01*
G01Y-9842D02*
X1503091D01*
G01X1459330Y25509D02*
Y28609D01*
X1458870Y27989D01*
G01Y25509D02*
X1459790D01*
G01X1490800Y177100D02*
X1495900D01*
Y157100D01*
X1502500D01*
Y130900D01*
X1495700D01*
Y89900D01*
X1475800D01*
Y176900D01*
X1482600D01*
G01X1472264Y99705D02*
X1465964D01*
Y101585D01*
X1466279Y102212D01*
X1467014Y102682D01*
X1467854Y102839D01*
X1468694Y102682D01*
X1469324Y102290D01*
X1469639Y101585D01*
Y99705D01*
G01X1472264Y106005D02*
X1465964D01*
Y107964D01*
X1466279Y108590D01*
X1466699Y108982D01*
X1467539Y109139D01*
X1468379Y108982D01*
X1468904Y108512D01*
X1469219Y107964D01*
Y106005D01*
G01Y107964D02*
X1472264Y109139D01*
G01Y115439D02*
Y112305D01*
X1465964D01*
Y115439D01*
G01X1469009Y114185D02*
Y112305D01*
G01X1471424Y118527D02*
X1471949Y119154D01*
X1472264Y119859D01*
Y120485D01*
X1471949Y121112D01*
X1471424Y121582D01*
X1470689Y121817D01*
X1469954Y121660D01*
X1469324Y121269D01*
X1468904Y120564D01*
X1468694Y119624D01*
X1468274Y119075D01*
X1467539Y118840D01*
X1466804Y118997D01*
X1466279Y119389D01*
X1465964Y119937D01*
Y120485D01*
X1466174Y121034D01*
X1466699Y121504D01*
G01X1471424Y124827D02*
X1471949Y125454D01*
X1472264Y126159D01*
Y126785D01*
X1471949Y127412D01*
X1471424Y127882D01*
X1470689Y128117D01*
X1469954Y127960D01*
X1469324Y127569D01*
X1468904Y126864D01*
X1468694Y125924D01*
X1468274Y125375D01*
X1467539Y125140D01*
X1466804Y125297D01*
X1466279Y125689D01*
X1465964Y126237D01*
Y126785D01*
X1466174Y127334D01*
X1466699Y127804D01*
G01X1470164Y131754D02*
Y133790D01*
G01X1472264Y137584D02*
X1465964D01*
Y140560D01*
G01X1469009Y139464D02*
Y137584D01*
G01X1465964Y144432D02*
Y146312D01*
G01Y145372D02*
X1472264D01*
G01Y144432D02*
Y146312D01*
G01X1465964Y151672D02*
X1472264D01*
G01X1465964Y149870D02*
Y153474D01*
G01X1482740Y91457D02*
X1476540D01*
Y94657D01*
X1482740D01*
Y91457D01*
G01Y96457D02*
X1476540D01*
Y99657D01*
X1482740D01*
Y96457D01*
G01X1478409Y85037D02*
X1478601Y84727D01*
X1478831Y84520D01*
X1479099Y84417D01*
X1479406Y84520D01*
X1479636Y84727D01*
X1479866Y85037D01*
X1479943Y85450D01*
Y87517D01*
G01X1481548Y85709D02*
X1481816Y86070D01*
X1482046Y86277D01*
X1482353Y86380D01*
X1482621Y86277D01*
X1482813Y86070D01*
X1482966Y85760D01*
X1483004Y85399D01*
X1482966Y85089D01*
X1482813Y84779D01*
X1482583Y84520D01*
X1482314Y84417D01*
X1482008Y84520D01*
X1481739Y84830D01*
X1481586Y85295D01*
X1481548Y85812D01*
X1481624Y86484D01*
X1481739Y86845D01*
X1481931Y87207D01*
X1482199Y87465D01*
X1482468Y87517D01*
X1482736Y87414D01*
X1482928Y87155D01*
G01X1482740Y101657D02*
X1476540D01*
Y104857D01*
X1482740D01*
Y101657D01*
G01Y107757D02*
X1476540D01*
Y110957D01*
X1482740D01*
Y107757D01*
G01X1477000Y114158D02*
Y120958D01*
X1492000D01*
Y114158D01*
X1477000D01*
G01X1480293Y142342D02*
X1480063Y142497D01*
X1479795Y142600D01*
X1479488D01*
X1479143Y142445D01*
X1478875Y142187D01*
X1478683Y141877D01*
X1478530Y141360D01*
X1478492Y140895D01*
X1478568Y140430D01*
X1478683Y140120D01*
X1478913Y139810D01*
X1479182Y139603D01*
X1479450Y139500D01*
X1479718D01*
X1479987Y139603D01*
X1480217Y139758D01*
X1480408Y139965D01*
G01X1476100Y144600D02*
X1482500D01*
Y136400D01*
X1476000D01*
G01X1477000Y122958D02*
Y129758D01*
X1492000D01*
Y122958D01*
X1477000D01*
G01X1480617Y168558D02*
Y171658D01*
X1480157Y171038D01*
G01Y168558D02*
X1481077D01*
G01X1478147Y166425D02*
X1494686D01*
Y158157D01*
X1478147D01*
Y166425D01*
G01X1477121Y148285D02*
Y151385D01*
X1476661Y150765D01*
G01Y148285D02*
X1477581D01*
G01X1478233Y156734D02*
X1494772D01*
Y148466D01*
X1478233D01*
Y156734D01*
G01X1478336Y187097D02*
X1478646Y187289D01*
X1478853Y187519D01*
X1478956Y187787D01*
X1478853Y188094D01*
X1478646Y188324D01*
X1478336Y188554D01*
X1477923Y188631D01*
X1475856D01*
G01X1478956Y190964D02*
X1475856D01*
X1476476Y190504D01*
G01X1478956D02*
Y191424D01*
G01Y193987D02*
X1478284Y194064D01*
X1477716Y194179D01*
X1477199Y194332D01*
X1476631Y194524D01*
X1475856Y194831D01*
Y193297D01*
G01X1503504Y-49508D02*
X1574370D01*
Y80611D01*
X1503504D01*
Y-49508D01*
G01X1486788Y94657D02*
X1492988D01*
Y91457D01*
X1486788D01*
Y94657D01*
G01Y99657D02*
X1492988D01*
Y96457D01*
X1486788D01*
Y99657D01*
G01X1500649Y88583D02*
X1500494Y88736D01*
X1500235Y88851D01*
X1499874Y88928D01*
X1499564Y88851D01*
X1499357Y88698D01*
X1499202Y88429D01*
Y87394D01*
X1502302D01*
Y88659D01*
X1502095Y88928D01*
X1501785Y89081D01*
X1501424Y89158D01*
X1501062Y89081D01*
X1500752Y88851D01*
X1500649Y88583D01*
Y87394D01*
G01X1502302Y91376D02*
X1499202D01*
X1499822Y90916D01*
G01X1502302D02*
Y91836D01*
G01X1501682Y93633D02*
X1502044Y93863D01*
X1502250Y94169D01*
X1502302Y94514D01*
X1502250Y94821D01*
X1501992Y95128D01*
X1501682Y95319D01*
X1501372Y95358D01*
X1501010Y95281D01*
X1500752Y95013D01*
X1500649Y94744D01*
Y94399D01*
G01Y94744D02*
X1500494Y94974D01*
X1500235Y95166D01*
X1499925Y95243D01*
X1499615Y95166D01*
X1499357Y94974D01*
X1499202Y94629D01*
X1499254Y94284D01*
X1499460Y93939D01*
G01X1532827Y78386D02*
X1503949D01*
Y103444D01*
G01X1486788Y104857D02*
X1492988D01*
Y101657D01*
X1486788D01*
Y104857D01*
G01Y110957D02*
X1492988D01*
Y107757D01*
X1486788D01*
Y110957D01*
G01X1501683Y114418D02*
X1498583Y115376D01*
X1501683Y116334D01*
G01X1500598Y115989D02*
Y114763D01*
G01X1501683Y118476D02*
X1498583D01*
X1499203Y118016D01*
G01X1501683D02*
Y118936D01*
G01X1501063Y120733D02*
X1501425Y120963D01*
X1501631Y121269D01*
X1501683Y121614D01*
X1501631Y121921D01*
X1501373Y122228D01*
X1501063Y122419D01*
X1500753Y122458D01*
X1500391Y122381D01*
X1500133Y122113D01*
X1500030Y121844D01*
Y121499D01*
G01Y121844D02*
X1499875Y122074D01*
X1499616Y122266D01*
X1499306Y122343D01*
X1498996Y122266D01*
X1498738Y122074D01*
X1498583Y121729D01*
X1498635Y121384D01*
X1498841Y121039D01*
G01X1497747Y109138D02*
X1498514D01*
Y108208D01*
X1498284Y107898D01*
X1498015Y107691D01*
X1497632Y107588D01*
X1497249Y107691D01*
X1496980Y107898D01*
X1496750Y108208D01*
X1496597Y108570D01*
X1496520Y108983D01*
Y109345D01*
X1496597Y109655D01*
X1496750Y110016D01*
X1496980Y110326D01*
X1497210Y110533D01*
X1497517Y110688D01*
X1497785D01*
X1498092Y110585D01*
X1498322Y110378D01*
G01X1499774Y108208D02*
X1500004Y107846D01*
X1500310Y107640D01*
X1500655Y107588D01*
X1500962Y107640D01*
X1501269Y107898D01*
X1501460Y108208D01*
X1501499Y108518D01*
X1501422Y108880D01*
X1501154Y109138D01*
X1500885Y109241D01*
X1500540D01*
G01X1500885D02*
X1501115Y109396D01*
X1501307Y109655D01*
X1501384Y109965D01*
X1501307Y110275D01*
X1501115Y110533D01*
X1500770Y110688D01*
X1500425Y110636D01*
X1500080Y110430D01*
G01X1503949Y113744D02*
Y132244D01*
G01X1499100Y140000D02*
X1492500D01*
G01X1499100Y132000D02*
X1492500D01*
G01X1492400D02*
Y147000D01*
G01X1499100Y139000D02*
X1492500D01*
G01X1499200Y147000D02*
Y132000D01*
G01X1490900Y140000D02*
X1484300D01*
G01X1490900Y132000D02*
X1484300D01*
G01X1484200D02*
Y147000D01*
G01X1490900Y139000D02*
X1484300D01*
G01X1491000Y147000D02*
Y132000D01*
G01X1499247Y128061D02*
X1500014D01*
Y127131D01*
X1499784Y126821D01*
X1499515Y126614D01*
X1499132Y126511D01*
X1498749Y126614D01*
X1498480Y126821D01*
X1498250Y127131D01*
X1498097Y127493D01*
X1498020Y127906D01*
Y128268D01*
X1498097Y128578D01*
X1498250Y128939D01*
X1498480Y129249D01*
X1498710Y129456D01*
X1499017Y129611D01*
X1499285D01*
X1499592Y129508D01*
X1499822Y129301D01*
G01X1501389Y129094D02*
X1501619Y129404D01*
X1501887Y129559D01*
X1502194Y129611D01*
X1502577Y129508D01*
X1502845Y129249D01*
X1502922Y128939D01*
X1502884Y128629D01*
X1502730Y128371D01*
X1501964Y127854D01*
X1501619Y127493D01*
X1501389Y126976D01*
X1501312Y126511D01*
X1502922D01*
G01X1503949Y132244D02*
Y162544D01*
G01X1496989Y163741D02*
X1497219Y164051D01*
X1497487Y164206D01*
X1497794Y164258D01*
X1498177Y164155D01*
X1498445Y163896D01*
X1498522Y163586D01*
X1498484Y163276D01*
X1498330Y163018D01*
X1497564Y162501D01*
X1497219Y162140D01*
X1496989Y161623D01*
X1496912Y161158D01*
X1498522D01*
G01X1496593Y152968D02*
X1496823Y153278D01*
X1497091Y153433D01*
X1497398Y153485D01*
X1497781Y153382D01*
X1498049Y153123D01*
X1498126Y152813D01*
X1498088Y152503D01*
X1497934Y152245D01*
X1497168Y151728D01*
X1496823Y151367D01*
X1496593Y150850D01*
X1496516Y150385D01*
X1498126D01*
G01X1499100Y147000D02*
X1492500D01*
G01X1490900D02*
X1484300D01*
G01X1498047Y170294D02*
X1498814D01*
Y169364D01*
X1498584Y169054D01*
X1498315Y168847D01*
X1497932Y168744D01*
X1497549Y168847D01*
X1497280Y169054D01*
X1497050Y169364D01*
X1496897Y169726D01*
X1496820Y170139D01*
Y170501D01*
X1496897Y170811D01*
X1497050Y171172D01*
X1497280Y171482D01*
X1497510Y171689D01*
X1497817Y171844D01*
X1498085D01*
X1498392Y171741D01*
X1498622Y171534D01*
G01X1500917Y168744D02*
Y171844D01*
X1500457Y171224D01*
G01Y168744D02*
X1501377D01*
G01X1500089Y180824D02*
X1502311D01*
X1502776Y180977D01*
X1503086Y181284D01*
X1503189Y181667D01*
X1503086Y182050D01*
X1502776Y182357D01*
X1502311Y182510D01*
X1500089D01*
G01X1502827Y184115D02*
X1503086Y184384D01*
X1503189Y184690D01*
X1503086Y184997D01*
X1502776Y185265D01*
X1502311Y185457D01*
X1501846Y185534D01*
X1501277D01*
X1500812Y185457D01*
X1500399Y185265D01*
X1500192Y185035D01*
X1500089Y184767D01*
X1500192Y184460D01*
X1500399Y184230D01*
X1500709Y184077D01*
X1501122Y184000D01*
X1501484Y184077D01*
X1501846Y184269D01*
X1502052Y184499D01*
X1502104Y184767D01*
X1502001Y185074D01*
X1501742Y185304D01*
X1501277Y185534D01*
G01X1503949Y173144D02*
Y172844D01*
Y198386D01*
X1669185D01*
Y172844D01*
G01X1562559Y68800D02*
X1515315D01*
Y-37697D01*
X1562559D01*
Y68800D01*
G01X1512444Y8256D02*
X1506144D01*
Y10136D01*
X1506459Y10763D01*
X1507194Y11233D01*
X1508034Y11390D01*
X1508874Y11233D01*
X1509504Y10841D01*
X1509819Y10136D01*
Y8256D01*
G01X1512444Y14556D02*
X1506144D01*
Y16515D01*
X1506459Y17141D01*
X1506879Y17533D01*
X1507719Y17690D01*
X1508559Y17533D01*
X1509084Y17063D01*
X1509399Y16515D01*
Y14556D01*
G01Y16515D02*
X1512444Y17690D01*
G01Y23990D02*
Y20856D01*
X1506144D01*
Y23990D01*
G01X1509189Y22736D02*
Y20856D01*
G01X1511604Y27078D02*
X1512129Y27705D01*
X1512444Y28410D01*
Y29036D01*
X1512129Y29663D01*
X1511604Y30133D01*
X1510869Y30368D01*
X1510134Y30211D01*
X1509504Y29820D01*
X1509084Y29115D01*
X1508874Y28175D01*
X1508454Y27626D01*
X1507719Y27391D01*
X1506984Y27548D01*
X1506459Y27940D01*
X1506144Y28488D01*
Y29036D01*
X1506354Y29585D01*
X1506879Y30055D01*
G01X1511604Y33378D02*
X1512129Y34005D01*
X1512444Y34710D01*
Y35336D01*
X1512129Y35963D01*
X1511604Y36433D01*
X1510869Y36668D01*
X1510134Y36511D01*
X1509504Y36120D01*
X1509084Y35415D01*
X1508874Y34475D01*
X1508454Y33926D01*
X1507719Y33691D01*
X1506984Y33848D01*
X1506459Y34240D01*
X1506144Y34788D01*
Y35336D01*
X1506354Y35885D01*
X1506879Y36355D01*
G01X1510344Y40305D02*
Y42341D01*
G01X1512444Y46135D02*
X1506144D01*
Y49111D01*
G01X1509189Y48015D02*
Y46135D01*
G01X1506144Y52983D02*
Y54863D01*
G01Y53923D02*
X1512444D01*
G01Y52983D02*
Y54863D01*
G01X1506144Y60223D02*
X1512444D01*
G01X1506144Y58421D02*
Y62025D01*
G01X1518120Y71182D02*
X1518388Y71543D01*
X1518618Y71750D01*
X1518925Y71853D01*
X1519193Y71750D01*
X1519385Y71543D01*
X1519538Y71233D01*
X1519576Y70872D01*
X1519538Y70562D01*
X1519385Y70252D01*
X1519155Y69993D01*
X1518886Y69890D01*
X1518580Y69993D01*
X1518311Y70303D01*
X1518158Y70768D01*
X1518120Y71285D01*
X1518196Y71957D01*
X1518311Y72318D01*
X1518503Y72680D01*
X1518771Y72938D01*
X1519040Y72990D01*
X1519308Y72887D01*
X1519500Y72628D01*
G01X1526205Y70255D02*
X1526435Y69997D01*
X1526703Y69842D01*
X1527048Y69790D01*
X1527393Y69893D01*
X1527661Y70100D01*
X1527853Y70462D01*
X1527891Y70875D01*
X1527815Y71288D01*
X1527623Y71547D01*
X1527355Y71753D01*
X1527086Y71805D01*
X1526818Y71753D01*
X1526473Y71547D01*
X1526588Y72890D01*
X1527623D01*
G01X1521791Y111850D02*
Y97401D01*
X1549153D01*
G01X1532827Y78386D02*
Y86693D01*
X1514205D01*
Y102944D01*
G01X1521791Y129850D02*
Y111850D01*
G01X1514205Y114344D02*
Y128044D01*
G01X1576515Y134650D02*
Y144645D01*
X1521791D01*
Y134650D01*
G01X1514205Y136444D02*
Y162044D01*
G01Y173344D02*
Y181850D01*
X1584067D01*
Y86693D01*
G01X1536808Y70090D02*
Y73190D01*
X1535390Y70968D01*
X1537306D01*
G01X1542605Y70810D02*
X1542835Y70448D01*
X1543141Y70242D01*
X1543486Y70190D01*
X1543793Y70242D01*
X1544100Y70500D01*
X1544291Y70810D01*
X1544330Y71120D01*
X1544253Y71482D01*
X1543985Y71740D01*
X1543716Y71843D01*
X1543371D01*
G01X1543716D02*
X1543946Y71998D01*
X1544138Y72257D01*
X1544215Y72567D01*
X1544138Y72877D01*
X1543946Y73135D01*
X1543601Y73290D01*
X1543256Y73238D01*
X1542911Y73032D01*
G01X1550220Y72973D02*
X1550450Y73283D01*
X1550718Y73438D01*
X1551025Y73490D01*
X1551408Y73387D01*
X1551676Y73128D01*
X1551753Y72818D01*
X1551715Y72508D01*
X1551561Y72250D01*
X1550795Y71733D01*
X1550450Y71372D01*
X1550220Y70855D01*
X1550143Y70390D01*
X1551753D01*
G01X1549153Y97401D02*
X1576515D01*
Y111850D01*
G01X1564190Y3799D02*
X1565148Y6899D01*
X1566106Y3799D01*
G01X1565761Y4884D02*
X1564535D01*
G01X1566228Y20613D02*
X1565998Y20768D01*
X1565730Y20871D01*
X1565423D01*
X1565078Y20716D01*
X1564810Y20458D01*
X1564618Y20148D01*
X1564465Y19631D01*
X1564427Y19166D01*
X1564503Y18701D01*
X1564618Y18391D01*
X1564848Y18081D01*
X1565117Y17874D01*
X1565385Y17771D01*
X1565653D01*
X1565922Y17874D01*
X1566152Y18029D01*
X1566343Y18236D01*
G01X1565892Y13736D02*
X1566045Y13891D01*
X1566160Y14150D01*
X1566237Y14511D01*
X1566160Y14821D01*
X1566007Y15028D01*
X1565738Y15183D01*
X1564703D01*
Y12083D01*
X1565968D01*
X1566237Y12290D01*
X1566390Y12600D01*
X1566467Y12961D01*
X1566390Y13323D01*
X1566160Y13633D01*
X1565892Y13736D01*
X1564703D01*
G01X1566152Y28647D02*
X1564618D01*
Y31747D01*
X1566152D01*
G01X1565538Y30249D02*
X1564618D01*
G01X1565042Y23459D02*
Y26559D01*
X1565808D01*
X1566115Y26404D01*
X1566345Y26197D01*
X1566537Y25887D01*
X1566690Y25526D01*
X1566728Y25009D01*
X1566690Y24492D01*
X1566537Y24131D01*
X1566345Y23821D01*
X1566115Y23614D01*
X1565808Y23459D01*
X1565042D01*
G01X1564557Y34135D02*
Y37235D01*
X1566013D01*
G01X1565477Y35737D02*
X1564557D01*
G01X1565415Y41473D02*
X1566182D01*
Y40543D01*
X1565952Y40233D01*
X1565683Y40026D01*
X1565300Y39923D01*
X1564917Y40026D01*
X1564648Y40233D01*
X1564418Y40543D01*
X1564265Y40905D01*
X1564188Y41318D01*
Y41680D01*
X1564265Y41990D01*
X1564418Y42351D01*
X1564648Y42661D01*
X1564878Y42868D01*
X1565185Y43023D01*
X1565453D01*
X1565760Y42920D01*
X1565990Y42713D01*
G01X1564380Y45112D02*
Y48212D01*
G01X1565990D02*
Y45112D01*
G01Y46662D02*
X1564380D01*
G01X1564925Y54300D02*
X1565845D01*
G01X1565385D02*
Y51200D01*
G01X1564925D02*
X1565845D01*
G01X1558548Y70590D02*
Y73690D01*
X1558088Y73070D01*
G01Y70590D02*
X1559008D01*
G01X1584067Y86693D02*
X1567079D01*
Y78386D01*
G01X1607669D02*
X1567079D01*
G01X1578581Y6161D02*
X1578891Y6353D01*
X1579098Y6583D01*
X1579201Y6851D01*
X1579098Y7158D01*
X1578891Y7388D01*
X1578581Y7618D01*
X1578168Y7695D01*
X1576101D01*
G01X1579201Y10028D02*
X1579149Y10296D01*
X1578994Y10603D01*
X1578736Y10795D01*
X1578374Y10871D01*
X1578013Y10795D01*
X1577703Y10565D01*
X1577548Y10220D01*
Y9836D01*
X1577444Y9606D01*
X1577186Y9415D01*
X1576824Y9338D01*
X1576463Y9453D01*
X1576204Y9721D01*
X1576101Y10028D01*
X1576204Y10335D01*
X1576463Y10603D01*
X1576824Y10718D01*
X1577186Y10641D01*
X1577444Y10450D01*
X1577548Y10220D01*
Y9836D01*
X1577703Y9491D01*
X1578013Y9261D01*
X1578374Y9185D01*
X1578736Y9261D01*
X1578994Y9453D01*
X1579149Y9760D01*
X1579201Y10028D01*
G01X1581205Y11040D02*
X1581832Y10515D01*
X1582537Y10200D01*
X1583163D01*
X1583790Y10515D01*
X1584260Y11040D01*
X1584495Y11775D01*
X1584338Y12510D01*
X1583947Y13140D01*
X1583242Y13560D01*
X1582302Y13770D01*
X1581753Y14190D01*
X1581518Y14925D01*
X1581675Y15660D01*
X1582067Y16185D01*
X1582615Y16500D01*
X1583163D01*
X1583712Y16290D01*
X1584182Y15765D01*
G01X1587192Y10200D02*
X1589150Y16500D01*
X1591108Y10200D01*
G01X1590403Y12405D02*
X1587897D01*
G01X1593805Y11040D02*
X1594432Y10515D01*
X1595137Y10200D01*
X1595763D01*
X1596390Y10515D01*
X1596860Y11040D01*
X1597095Y11775D01*
X1596938Y12510D01*
X1596547Y13140D01*
X1595842Y13560D01*
X1594902Y13770D01*
X1594353Y14190D01*
X1594118Y14925D01*
X1594275Y15660D01*
X1594667Y16185D01*
X1595215Y16500D01*
X1595763D01*
X1596312Y16290D01*
X1596782Y15765D01*
G01X1575692Y20700D02*
X1577650Y27000D01*
X1579608Y20700D01*
G01X1578903Y22905D02*
X1576397D01*
G01X1583010Y27000D02*
X1584890D01*
G01X1583950D02*
Y20700D01*
G01X1583010D02*
X1584890D01*
G01X1588683D02*
Y27000D01*
X1590642D01*
X1591268Y26685D01*
X1591660Y26265D01*
X1591817Y25425D01*
X1591660Y24585D01*
X1591190Y24060D01*
X1590642Y23745D01*
X1588683D01*
G01X1590642D02*
X1591817Y20700D01*
G01X1594513D02*
Y27000D01*
X1596550Y21750D01*
X1598587Y27000D01*
Y20700D01*
G01X1600892D02*
X1602850Y27000D01*
X1604808Y20700D01*
G01X1604103Y22905D02*
X1601597D01*
G01X1607505Y20700D02*
X1610795Y27000D01*
G01X1607505D02*
X1610795Y20700D01*
G01X1579290Y48200D02*
Y54500D01*
X1576392Y49985D01*
X1580308D01*
G01X1582300Y50300D02*
X1583083Y52400D01*
X1583867D01*
X1585433Y48200D01*
X1586217D01*
X1587000Y50300D01*
G01X1590793Y48200D02*
X1590950Y49565D01*
X1591185Y50720D01*
X1591498Y51770D01*
X1591890Y52925D01*
X1592517Y54500D01*
X1589383D01*
G01X1576505Y63840D02*
X1577132Y63315D01*
X1577837Y63000D01*
X1578463D01*
X1579090Y63315D01*
X1579560Y63840D01*
X1579795Y64575D01*
X1579638Y65310D01*
X1579247Y65940D01*
X1578542Y66360D01*
X1577602Y66570D01*
X1577053Y66990D01*
X1576818Y67725D01*
X1576975Y68460D01*
X1577367Y68985D01*
X1577915Y69300D01*
X1578463D01*
X1579012Y69090D01*
X1579482Y68565D01*
G01X1582492Y63000D02*
X1584450Y69300D01*
X1586408Y63000D01*
G01X1585703Y65205D02*
X1583197D01*
G01X1589105Y63840D02*
X1589732Y63315D01*
X1590437Y63000D01*
X1591063D01*
X1591690Y63315D01*
X1592160Y63840D01*
X1592395Y64575D01*
X1592238Y65310D01*
X1591847Y65940D01*
X1591142Y66360D01*
X1590202Y66570D01*
X1589653Y66990D01*
X1589418Y67725D01*
X1589575Y68460D01*
X1589967Y68985D01*
X1590515Y69300D01*
X1591063D01*
X1591612Y69090D01*
X1592082Y68565D01*
G01X1585408Y71851D02*
X1585561Y72006D01*
X1585676Y72265D01*
X1585753Y72626D01*
X1585676Y72936D01*
X1585523Y73143D01*
X1585254Y73298D01*
X1584219D01*
Y70198D01*
X1585484D01*
X1585753Y70405D01*
X1585906Y70715D01*
X1585983Y71076D01*
X1585906Y71438D01*
X1585676Y71748D01*
X1585408Y71851D01*
X1584219D01*
G01X1588201Y70198D02*
Y73298D01*
X1587741Y72678D01*
G01Y70198D02*
X1588661D01*
G01X1583943Y74117D02*
X1584901Y77217D01*
X1585859Y74117D01*
G01X1585514Y75202D02*
X1584288D01*
G01X1588001Y74117D02*
Y77217D01*
X1587541Y76597D01*
G01Y74117D02*
X1588461D01*
G01X1577454Y76117D02*
Y73895D01*
X1577607Y73430D01*
X1577914Y73120D01*
X1578297Y73017D01*
X1578680Y73120D01*
X1578987Y73430D01*
X1579140Y73895D01*
Y76117D01*
G01X1581857Y73017D02*
Y76117D01*
X1580439Y73895D01*
X1582355D01*
G01X1607669Y86693D02*
X1589067D01*
Y181850D01*
X1658929D01*
Y173344D01*
G01X1576515Y111850D02*
Y129750D01*
G01X1633100Y36200D02*
Y24800D01*
X1611800D01*
Y69800D01*
X1613200D01*
G01X1613343Y26110D02*
Y29210D01*
X1614302D01*
X1614608Y29055D01*
X1614800Y28848D01*
X1614877Y28435D01*
X1614800Y28022D01*
X1614570Y27763D01*
X1614302Y27608D01*
X1613343D01*
G01X1614302D02*
X1614877Y26110D01*
G01X1617210D02*
Y29210D01*
X1616750Y28590D01*
G01Y26110D02*
X1617670D01*
G01X1620233D02*
X1620310Y26782D01*
X1620425Y27350D01*
X1620578Y27867D01*
X1620770Y28435D01*
X1621077Y29210D01*
X1619543D01*
G01X1613143Y30810D02*
Y33910D01*
X1614102D01*
X1614408Y33755D01*
X1614600Y33548D01*
X1614677Y33135D01*
X1614600Y32722D01*
X1614370Y32463D01*
X1614102Y32308D01*
X1613143D01*
G01X1614102D02*
X1614677Y30810D01*
G01X1617010D02*
Y33910D01*
X1616550Y33290D01*
G01Y30810D02*
X1617470D01*
G01X1619458Y31172D02*
X1619727Y30913D01*
X1620033Y30810D01*
X1620340Y30913D01*
X1620608Y31223D01*
X1620800Y31688D01*
X1620877Y32153D01*
Y32722D01*
X1620800Y33187D01*
X1620608Y33600D01*
X1620378Y33807D01*
X1620110Y33910D01*
X1619803Y33807D01*
X1619573Y33600D01*
X1619420Y33290D01*
X1619343Y32877D01*
X1619420Y32515D01*
X1619612Y32153D01*
X1619842Y31947D01*
X1620110Y31895D01*
X1620417Y31998D01*
X1620647Y32257D01*
X1620877Y32722D01*
G01X1613043Y35510D02*
Y38610D01*
X1614002D01*
X1614308Y38455D01*
X1614500Y38248D01*
X1614577Y37835D01*
X1614500Y37422D01*
X1614270Y37163D01*
X1614002Y37008D01*
X1613043D01*
G01X1614002D02*
X1614577Y35510D01*
G01X1616182Y38093D02*
X1616412Y38403D01*
X1616680Y38558D01*
X1616987Y38610D01*
X1617370Y38507D01*
X1617638Y38248D01*
X1617715Y37938D01*
X1617677Y37628D01*
X1617523Y37370D01*
X1616757Y36853D01*
X1616412Y36492D01*
X1616182Y35975D01*
X1616105Y35510D01*
X1617715D01*
G01X1619933D02*
X1620010Y36182D01*
X1620125Y36750D01*
X1620278Y37267D01*
X1620470Y37835D01*
X1620777Y38610D01*
X1619243D01*
G01X1613243Y40110D02*
Y43210D01*
X1614202D01*
X1614508Y43055D01*
X1614700Y42848D01*
X1614777Y42435D01*
X1614700Y42022D01*
X1614470Y41763D01*
X1614202Y41608D01*
X1613243D01*
G01X1614202D02*
X1614777Y40110D01*
G01X1616267Y40730D02*
X1616497Y40368D01*
X1616803Y40162D01*
X1617148Y40110D01*
X1617455Y40162D01*
X1617762Y40420D01*
X1617953Y40730D01*
X1617992Y41040D01*
X1617915Y41402D01*
X1617647Y41660D01*
X1617378Y41763D01*
X1617033D01*
G01X1617378D02*
X1617608Y41918D01*
X1617800Y42177D01*
X1617877Y42487D01*
X1617800Y42797D01*
X1617608Y43055D01*
X1617263Y43210D01*
X1616918Y43158D01*
X1616573Y42952D01*
G01X1620210Y40110D02*
Y43210D01*
X1619750Y42590D01*
G01Y40110D02*
X1620670D01*
G01X1619383Y45042D02*
Y48142D01*
X1620342D01*
X1620648Y47987D01*
X1620840Y47780D01*
X1620917Y47367D01*
X1620840Y46954D01*
X1620610Y46695D01*
X1620342Y46540D01*
X1619383D01*
G01X1620342D02*
X1620917Y45042D01*
G01X1623250D02*
X1623518Y45094D01*
X1623825Y45249D01*
X1624017Y45507D01*
X1624093Y45869D01*
X1624017Y46230D01*
X1623787Y46540D01*
X1623442Y46695D01*
X1623058D01*
X1622828Y46799D01*
X1622637Y47057D01*
X1622560Y47419D01*
X1622675Y47780D01*
X1622943Y48039D01*
X1623250Y48142D01*
X1623557Y48039D01*
X1623825Y47780D01*
X1623940Y47419D01*
X1623863Y47057D01*
X1623672Y46799D01*
X1623442Y46695D01*
X1623058D01*
X1622713Y46540D01*
X1622483Y46230D01*
X1622407Y45869D01*
X1622483Y45507D01*
X1622675Y45249D01*
X1622982Y45094D01*
X1623250Y45042D01*
G01X1626350Y48142D02*
X1626043Y48039D01*
X1625813Y47780D01*
X1625660Y47470D01*
X1625545Y47057D01*
X1625507Y46592D01*
X1625545Y46127D01*
X1625660Y45714D01*
X1625813Y45404D01*
X1626043Y45145D01*
X1626350Y45042D01*
X1626657Y45145D01*
X1626887Y45404D01*
X1627040Y45714D01*
X1627155Y46127D01*
X1627193Y46592D01*
X1627155Y47057D01*
X1627040Y47470D01*
X1626887Y47780D01*
X1626657Y48039D01*
X1626350Y48142D01*
G01X1616393Y65142D02*
X1616163Y65297D01*
X1615895Y65400D01*
X1615588D01*
X1615243Y65245D01*
X1614975Y64987D01*
X1614783Y64677D01*
X1614630Y64160D01*
X1614592Y63695D01*
X1614668Y63230D01*
X1614783Y62920D01*
X1615013Y62610D01*
X1615282Y62403D01*
X1615550Y62300D01*
X1615818D01*
X1616087Y62403D01*
X1616317Y62558D01*
X1616508Y62765D01*
G01X1613200Y69800D02*
X1633100D01*
Y50700D01*
G01X1611900Y59400D02*
X1617500D01*
Y69800D01*
G01X1618600Y55383D02*
X1621700D01*
Y56917D01*
G01Y59173D02*
X1621028Y59250D01*
X1620460Y59365D01*
X1619943Y59518D01*
X1619375Y59710D01*
X1618600Y60017D01*
Y58483D01*
G01X1600440Y71851D02*
X1600593Y72006D01*
X1600708Y72265D01*
X1600785Y72626D01*
X1600708Y72936D01*
X1600555Y73143D01*
X1600286Y73298D01*
X1599251D01*
Y70198D01*
X1600516D01*
X1600785Y70405D01*
X1600938Y70715D01*
X1601015Y71076D01*
X1600938Y71438D01*
X1600708Y71748D01*
X1600440Y71851D01*
X1599251D01*
G01X1603233Y70198D02*
Y73298D01*
X1602773Y72678D01*
G01Y70198D02*
X1603693D01*
G01X1605490Y70818D02*
X1605720Y70456D01*
X1606026Y70250D01*
X1606371Y70198D01*
X1606678Y70250D01*
X1606985Y70508D01*
X1607176Y70818D01*
X1607215Y71128D01*
X1607138Y71490D01*
X1606870Y71748D01*
X1606601Y71851D01*
X1606256D01*
G01X1606601D02*
X1606831Y72006D01*
X1607023Y72265D01*
X1607100Y72575D01*
X1607023Y72885D01*
X1606831Y73143D01*
X1606486Y73298D01*
X1606141Y73246D01*
X1605796Y73040D01*
G01X1599175Y74217D02*
X1600133Y77317D01*
X1601091Y74217D01*
G01X1600746Y75302D02*
X1599520D01*
G01X1603233Y74217D02*
Y77317D01*
X1602773Y76697D01*
G01Y74217D02*
X1603693D01*
G01X1605490Y74837D02*
X1605720Y74475D01*
X1606026Y74269D01*
X1606371Y74217D01*
X1606678Y74269D01*
X1606985Y74527D01*
X1607176Y74837D01*
X1607215Y75147D01*
X1607138Y75509D01*
X1606870Y75767D01*
X1606601Y75870D01*
X1606256D01*
G01X1606601D02*
X1606831Y76025D01*
X1607023Y76284D01*
X1607100Y76594D01*
X1607023Y76904D01*
X1606831Y77162D01*
X1606486Y77317D01*
X1606141Y77265D01*
X1605796Y77059D01*
G01X1596634Y111850D02*
Y97401D01*
X1623996D01*
G01X1607669Y78386D02*
Y86693D01*
G01X1596634Y129850D02*
Y111850D01*
G01X1651358Y134650D02*
Y144645D01*
X1596634D01*
Y134650D01*
G01X1702008Y18504D02*
G03I-31496J0D01*
G01X1622271Y26524D02*
Y29624D01*
X1623230D01*
X1623536Y29469D01*
X1623728Y29262D01*
X1623805Y28849D01*
X1623728Y28436D01*
X1623498Y28177D01*
X1623230Y28022D01*
X1622271D01*
G01X1623230D02*
X1623805Y26524D01*
G01X1625295Y26989D02*
X1625525Y26731D01*
X1625793Y26576D01*
X1626138Y26524D01*
X1626483Y26627D01*
X1626751Y26834D01*
X1626943Y27196D01*
X1626981Y27609D01*
X1626905Y28022D01*
X1626713Y28281D01*
X1626445Y28487D01*
X1626176Y28539D01*
X1625908Y28487D01*
X1625563Y28281D01*
X1625678Y29624D01*
X1626713D01*
G01X1629238D02*
X1628931Y29521D01*
X1628701Y29262D01*
X1628548Y28952D01*
X1628433Y28539D01*
X1628395Y28074D01*
X1628433Y27609D01*
X1628548Y27196D01*
X1628701Y26886D01*
X1628931Y26627D01*
X1629238Y26524D01*
X1629545Y26627D01*
X1629775Y26886D01*
X1629928Y27196D01*
X1630043Y27609D01*
X1630081Y28074D01*
X1630043Y28539D01*
X1629928Y28952D01*
X1629775Y29262D01*
X1629545Y29521D01*
X1629238Y29624D01*
G01X1622271Y31024D02*
Y34124D01*
X1623230D01*
X1623536Y33969D01*
X1623728Y33762D01*
X1623805Y33349D01*
X1623728Y32936D01*
X1623498Y32677D01*
X1623230Y32522D01*
X1622271D01*
G01X1623230D02*
X1623805Y31024D01*
G01X1625295Y31489D02*
X1625525Y31231D01*
X1625793Y31076D01*
X1626138Y31024D01*
X1626483Y31127D01*
X1626751Y31334D01*
X1626943Y31696D01*
X1626981Y32109D01*
X1626905Y32522D01*
X1626713Y32781D01*
X1626445Y32987D01*
X1626176Y33039D01*
X1625908Y32987D01*
X1625563Y32781D01*
X1625678Y34124D01*
X1626713D01*
G01X1629238Y31024D02*
Y34124D01*
X1628778Y33504D01*
G01Y31024D02*
X1629698D01*
G01X1639550Y55900D02*
X1638923Y55690D01*
X1638453Y55165D01*
X1638140Y54535D01*
X1637905Y53695D01*
X1637827Y52750D01*
X1637905Y51805D01*
X1638140Y50965D01*
X1638453Y50335D01*
X1638923Y49810D01*
X1639550Y49600D01*
X1640177Y49810D01*
X1640647Y50335D01*
X1640960Y50965D01*
X1641195Y51805D01*
X1641273Y52750D01*
X1641195Y53695D01*
X1640960Y54535D01*
X1640647Y55165D01*
X1640177Y55690D01*
X1639550Y55900D01*
G01X1643500Y51700D02*
X1644283Y53800D01*
X1645067D01*
X1646633Y49600D01*
X1647417D01*
X1648200Y51700D01*
G01X1650427Y50860D02*
X1650897Y50125D01*
X1651523Y49705D01*
X1652228Y49600D01*
X1652855Y49705D01*
X1653482Y50230D01*
X1653873Y50860D01*
X1653952Y51490D01*
X1653795Y52225D01*
X1653247Y52750D01*
X1652698Y52960D01*
X1651993D01*
G01X1652698D02*
X1653168Y53275D01*
X1653560Y53800D01*
X1653717Y54430D01*
X1653560Y55060D01*
X1653168Y55585D01*
X1652463Y55900D01*
X1651758Y55795D01*
X1651053Y55375D01*
G01X1622171Y35424D02*
Y38524D01*
X1623130D01*
X1623436Y38369D01*
X1623628Y38162D01*
X1623705Y37749D01*
X1623628Y37336D01*
X1623398Y37077D01*
X1623130Y36922D01*
X1622171D01*
G01X1623130D02*
X1623705Y35424D01*
G01X1626498D02*
Y38524D01*
X1625080Y36302D01*
X1626996D01*
G01X1629138Y35424D02*
X1629406Y35476D01*
X1629713Y35631D01*
X1629905Y35889D01*
X1629981Y36251D01*
X1629905Y36612D01*
X1629675Y36922D01*
X1629330Y37077D01*
X1628946D01*
X1628716Y37181D01*
X1628525Y37439D01*
X1628448Y37801D01*
X1628563Y38162D01*
X1628831Y38421D01*
X1629138Y38524D01*
X1629445Y38421D01*
X1629713Y38162D01*
X1629828Y37801D01*
X1629751Y37439D01*
X1629560Y37181D01*
X1629330Y37077D01*
X1628946D01*
X1628601Y36922D01*
X1628371Y36612D01*
X1628295Y36251D01*
X1628371Y35889D01*
X1628563Y35631D01*
X1628870Y35476D01*
X1629138Y35424D01*
G01X1622071Y39824D02*
Y42924D01*
X1623030D01*
X1623336Y42769D01*
X1623528Y42562D01*
X1623605Y42149D01*
X1623528Y41736D01*
X1623298Y41477D01*
X1623030Y41322D01*
X1622071D01*
G01X1623030D02*
X1623605Y39824D01*
G01X1626398D02*
Y42924D01*
X1624980Y40702D01*
X1626896D01*
G01X1628386Y40186D02*
X1628655Y39927D01*
X1628961Y39824D01*
X1629268Y39927D01*
X1629536Y40237D01*
X1629728Y40702D01*
X1629805Y41167D01*
Y41736D01*
X1629728Y42201D01*
X1629536Y42614D01*
X1629306Y42821D01*
X1629038Y42924D01*
X1628731Y42821D01*
X1628501Y42614D01*
X1628348Y42304D01*
X1628271Y41891D01*
X1628348Y41529D01*
X1628540Y41167D01*
X1628770Y40961D01*
X1629038Y40909D01*
X1629345Y41012D01*
X1629575Y41271D01*
X1629805Y41736D01*
G01X1619883Y49142D02*
Y52242D01*
X1620842D01*
X1621148Y52087D01*
X1621340Y51880D01*
X1621417Y51467D01*
X1621340Y51054D01*
X1621110Y50795D01*
X1620842Y50640D01*
X1619883D01*
G01X1620842D02*
X1621417Y49142D01*
G01X1623750D02*
X1624018Y49194D01*
X1624325Y49349D01*
X1624517Y49607D01*
X1624593Y49969D01*
X1624517Y50330D01*
X1624287Y50640D01*
X1623942Y50795D01*
X1623558D01*
X1623328Y50899D01*
X1623137Y51157D01*
X1623060Y51519D01*
X1623175Y51880D01*
X1623443Y52139D01*
X1623750Y52242D01*
X1624057Y52139D01*
X1624325Y51880D01*
X1624440Y51519D01*
X1624363Y51157D01*
X1624172Y50899D01*
X1623942Y50795D01*
X1623558D01*
X1623213Y50640D01*
X1622983Y50330D01*
X1622907Y49969D01*
X1622983Y49607D01*
X1623175Y49349D01*
X1623482Y49194D01*
X1623750Y49142D01*
G01X1626850D02*
Y52242D01*
X1626390Y51622D01*
G01Y49142D02*
X1627310D01*
G01X1637905Y60040D02*
X1638532Y59515D01*
X1639237Y59200D01*
X1639863D01*
X1640490Y59515D01*
X1640960Y60040D01*
X1641195Y60775D01*
X1641038Y61510D01*
X1640647Y62140D01*
X1639942Y62560D01*
X1639002Y62770D01*
X1638453Y63190D01*
X1638218Y63925D01*
X1638375Y64660D01*
X1638767Y65185D01*
X1639315Y65500D01*
X1639863D01*
X1640412Y65290D01*
X1640882Y64765D01*
G01X1643892Y59200D02*
X1645850Y65500D01*
X1647808Y59200D01*
G01X1647103Y61405D02*
X1644597D01*
G01X1650505Y60040D02*
X1651132Y59515D01*
X1651837Y59200D01*
X1652463D01*
X1653090Y59515D01*
X1653560Y60040D01*
X1653795Y60775D01*
X1653638Y61510D01*
X1653247Y62140D01*
X1652542Y62560D01*
X1651602Y62770D01*
X1651053Y63190D01*
X1650818Y63925D01*
X1650975Y64660D01*
X1651367Y65185D01*
X1651915Y65500D01*
X1652463D01*
X1653012Y65290D01*
X1653482Y64765D01*
G01X1620140Y65458D02*
Y68558D01*
X1621596D01*
G01X1621060Y67060D02*
X1620140D01*
G01X1623163Y65871D02*
X1623470Y65613D01*
X1623815Y65458D01*
X1624121D01*
X1624428Y65613D01*
X1624658Y65871D01*
X1624773Y66233D01*
X1624696Y66595D01*
X1624505Y66905D01*
X1624160Y67111D01*
X1623700Y67215D01*
X1623431Y67421D01*
X1623316Y67783D01*
X1623393Y68145D01*
X1623585Y68403D01*
X1623853Y68558D01*
X1624121D01*
X1624390Y68455D01*
X1624620Y68196D01*
G01X1626225Y65923D02*
X1626455Y65665D01*
X1626723Y65510D01*
X1627068Y65458D01*
X1627413Y65561D01*
X1627681Y65768D01*
X1627873Y66130D01*
X1627911Y66543D01*
X1627835Y66956D01*
X1627643Y67215D01*
X1627375Y67421D01*
X1627106Y67473D01*
X1626838Y67421D01*
X1626493Y67215D01*
X1626608Y68558D01*
X1627643D01*
G01X1620044Y61185D02*
Y64285D01*
X1621500D01*
G01X1620964Y62787D02*
X1620044D01*
G01X1623067Y61598D02*
X1623374Y61340D01*
X1623719Y61185D01*
X1624025D01*
X1624332Y61340D01*
X1624562Y61598D01*
X1624677Y61960D01*
X1624600Y62322D01*
X1624409Y62632D01*
X1624064Y62838D01*
X1623604Y62942D01*
X1623335Y63148D01*
X1623220Y63510D01*
X1623297Y63872D01*
X1623489Y64130D01*
X1623757Y64285D01*
X1624025D01*
X1624294Y64182D01*
X1624524Y63923D01*
G01X1626895Y61185D02*
X1626972Y61857D01*
X1627087Y62425D01*
X1627240Y62942D01*
X1627432Y63510D01*
X1627739Y64285D01*
X1626205D01*
G01X1625900Y55483D02*
X1629000D01*
Y57017D01*
G01X1628535Y58507D02*
X1628793Y58737D01*
X1628948Y59005D01*
X1629000Y59350D01*
X1628897Y59695D01*
X1628690Y59963D01*
X1628328Y60155D01*
X1627915Y60193D01*
X1627502Y60117D01*
X1627243Y59925D01*
X1627037Y59657D01*
X1626985Y59388D01*
X1627037Y59120D01*
X1627243Y58775D01*
X1625900Y58890D01*
Y59925D01*
G01X1623996Y97401D02*
X1651358D01*
Y111850D01*
G01X1658929Y102944D02*
Y86693D01*
X1641921D01*
Y78386D01*
G01X1669185Y103444D02*
Y78386D01*
X1641921D01*
G01X1665233Y53863D02*
Y56963D01*
G01X1666843D02*
Y53863D01*
G01Y55413D02*
X1665233D01*
G01X1669138Y53863D02*
X1669406Y53915D01*
X1669713Y54070D01*
X1669905Y54328D01*
X1669981Y54690D01*
X1669905Y55051D01*
X1669675Y55361D01*
X1669330Y55516D01*
X1668946D01*
X1668716Y55620D01*
X1668525Y55878D01*
X1668448Y56240D01*
X1668563Y56601D01*
X1668831Y56860D01*
X1669138Y56963D01*
X1669445Y56860D01*
X1669713Y56601D01*
X1669828Y56240D01*
X1669751Y55878D01*
X1669560Y55620D01*
X1669330Y55516D01*
X1668946D01*
X1668601Y55361D01*
X1668371Y55051D01*
X1668295Y54690D01*
X1668371Y54328D01*
X1668563Y54070D01*
X1668870Y53915D01*
X1669138Y53863D01*
G01X1653811Y75417D02*
Y73195D01*
X1653964Y72730D01*
X1654271Y72420D01*
X1654654Y72317D01*
X1655037Y72420D01*
X1655344Y72730D01*
X1655497Y73195D01*
Y75417D01*
G01X1657026Y74900D02*
X1657256Y75210D01*
X1657524Y75365D01*
X1657831Y75417D01*
X1658214Y75314D01*
X1658482Y75055D01*
X1658559Y74745D01*
X1658521Y74435D01*
X1658367Y74177D01*
X1657601Y73660D01*
X1657256Y73299D01*
X1657026Y72782D01*
X1656949Y72317D01*
X1658559D01*
G01X1651358Y111850D02*
Y129750D01*
G01X1658929Y128044D02*
Y114344D01*
G01Y161944D02*
Y136544D01*
G01X1678858Y76755D02*
Y77522D01*
X1679788D01*
X1680098Y77292D01*
X1680305Y77023D01*
X1680408Y76640D01*
X1680305Y76257D01*
X1680098Y75988D01*
X1679788Y75758D01*
X1679426Y75605D01*
X1679013Y75528D01*
X1678651D01*
X1678341Y75605D01*
X1677980Y75758D01*
X1677670Y75988D01*
X1677463Y76218D01*
X1677308Y76525D01*
Y76793D01*
X1677411Y77100D01*
X1677618Y77330D01*
G01X1680408Y78743D02*
X1677308D01*
X1680408Y80507D01*
X1677308D01*
G01X1680408Y81882D02*
X1677308D01*
Y82648D01*
X1677463Y82955D01*
X1677670Y83185D01*
X1677980Y83377D01*
X1678341Y83530D01*
X1678858Y83568D01*
X1679375Y83530D01*
X1679736Y83377D01*
X1680046Y83185D01*
X1680253Y82955D01*
X1680408Y82648D01*
Y81882D01*
G01Y85058D02*
X1677308D01*
Y85978D01*
X1677463Y86285D01*
X1677825Y86515D01*
X1678238Y86592D01*
X1678651Y86515D01*
X1678961Y86323D01*
X1679116Y85978D01*
Y85058D01*
G01X1680408Y87967D02*
X1677308Y88925D01*
X1680408Y89883D01*
G01X1679323Y89538D02*
Y88312D01*
G01X1680408Y91182D02*
X1677308D01*
Y91948D01*
X1677463Y92255D01*
X1677670Y92485D01*
X1677980Y92677D01*
X1678341Y92830D01*
X1678858Y92868D01*
X1679375Y92830D01*
X1679736Y92677D01*
X1680046Y92485D01*
X1680253Y92255D01*
X1680408Y91948D01*
Y91182D01*
G01Y95125D02*
X1677308D01*
X1677928Y94665D01*
G01X1680408D02*
Y95585D01*
G01X1671765Y87351D02*
X1671918Y87506D01*
X1672033Y87765D01*
X1672110Y88126D01*
X1672033Y88436D01*
X1671880Y88643D01*
X1671611Y88798D01*
X1670576D01*
Y85698D01*
X1671841D01*
X1672110Y85905D01*
X1672263Y86215D01*
X1672340Y86576D01*
X1672263Y86938D01*
X1672033Y87248D01*
X1671765Y87351D01*
X1670576D01*
G01X1674558Y85698D02*
Y88798D01*
X1674098Y88178D01*
G01Y85698D02*
X1675018D01*
G01X1669900Y95317D02*
X1670858Y98417D01*
X1671816Y95317D01*
G01X1671471Y96402D02*
X1670245D01*
G01X1673958Y95317D02*
Y98417D01*
X1673498Y97797D01*
G01Y95317D02*
X1674418D01*
G01X1671347Y92038D02*
X1672114D01*
Y91108D01*
X1671884Y90798D01*
X1671615Y90591D01*
X1671232Y90488D01*
X1670849Y90591D01*
X1670580Y90798D01*
X1670350Y91108D01*
X1670197Y91470D01*
X1670120Y91883D01*
Y92245D01*
X1670197Y92555D01*
X1670350Y92916D01*
X1670580Y93226D01*
X1670810Y93433D01*
X1671117Y93588D01*
X1671385D01*
X1671692Y93485D01*
X1671922Y93278D01*
G01X1673489Y91780D02*
X1673757Y92141D01*
X1673987Y92348D01*
X1674294Y92451D01*
X1674562Y92348D01*
X1674754Y92141D01*
X1674907Y91831D01*
X1674945Y91470D01*
X1674907Y91160D01*
X1674754Y90850D01*
X1674524Y90591D01*
X1674255Y90488D01*
X1673949Y90591D01*
X1673680Y90901D01*
X1673527Y91366D01*
X1673489Y91883D01*
X1673565Y92555D01*
X1673680Y92916D01*
X1673872Y93278D01*
X1674140Y93536D01*
X1674409Y93588D01*
X1674677Y93485D01*
X1674869Y93226D01*
G01X1671247Y101161D02*
X1672014D01*
Y100231D01*
X1671784Y99921D01*
X1671515Y99714D01*
X1671132Y99611D01*
X1670749Y99714D01*
X1670480Y99921D01*
X1670250Y100231D01*
X1670097Y100593D01*
X1670020Y101006D01*
Y101368D01*
X1670097Y101678D01*
X1670250Y102039D01*
X1670480Y102349D01*
X1670710Y102556D01*
X1671017Y102711D01*
X1671285D01*
X1671592Y102608D01*
X1671822Y102401D01*
G01X1673274Y100076D02*
X1673504Y99818D01*
X1673772Y99663D01*
X1674117Y99611D01*
X1674462Y99714D01*
X1674730Y99921D01*
X1674922Y100283D01*
X1674960Y100696D01*
X1674884Y101109D01*
X1674692Y101368D01*
X1674424Y101574D01*
X1674155Y101626D01*
X1673887Y101574D01*
X1673542Y101368D01*
X1673657Y102711D01*
X1674692D01*
G01X1669185Y162544D02*
Y113744D01*
G01X1673547Y168194D02*
X1674314D01*
Y167264D01*
X1674084Y166954D01*
X1673815Y166747D01*
X1673432Y166644D01*
X1673049Y166747D01*
X1672780Y166954D01*
X1672550Y167264D01*
X1672397Y167626D01*
X1672320Y168039D01*
Y168401D01*
X1672397Y168711D01*
X1672550Y169072D01*
X1672780Y169382D01*
X1673010Y169589D01*
X1673317Y169744D01*
X1673585D01*
X1673892Y169641D01*
X1674122Y169434D01*
G01X1676877Y166644D02*
Y169744D01*
X1675459Y167522D01*
X1677375D01*
G54D11*
G01X969700Y9760D02*
X971460D01*
G01X969700Y9920D02*
X971460D01*
G01X969700Y10080D02*
X971460D01*
G01X969700Y10240D02*
X971460D01*
G01X969700Y10400D02*
X971460D01*
G01X969700Y10560D02*
X971460D01*
G01X969700Y10720D02*
X971460D01*
G01X969700Y10880D02*
X971460D01*
G01X969700Y11040D02*
X971460D01*
G01X969700Y11200D02*
X971460D01*
G01X969700Y11360D02*
X971460D01*
G01X969700Y11520D02*
X971460D01*
G01X969700Y11680D02*
X971460D01*
G01X969700Y11840D02*
X971460D01*
G01X969700Y12000D02*
X971460D01*
G01X969700Y12160D02*
X971460D01*
G01X969700Y12320D02*
X971460D01*
G01X969700Y12480D02*
X971460D01*
G01X969700Y12640D02*
X971460D01*
G01X969700Y12800D02*
X971460D01*
G01X969700Y12960D02*
X971460D01*
G01X969700Y13120D02*
X971460D01*
G01X969700Y13280D02*
X971460D01*
G01X969700Y13440D02*
X971460D01*
G01X969700Y13600D02*
X971460D01*
G01X969700Y13760D02*
X971460D01*
G01X969700Y13920D02*
X971460D01*
G01X969700Y14080D02*
X971460D01*
G01X969700Y14240D02*
X971460D01*
G01X969700Y14400D02*
X971460D01*
G01X969700Y14560D02*
X971460D01*
G01X969700Y14720D02*
X971460D01*
G01X969700Y14880D02*
X971460D01*
G01X969700Y15040D02*
X971460D01*
G01X969700Y15200D02*
X971460D01*
G01X969700Y15360D02*
X971460D01*
G01X969700Y15520D02*
X971460D01*
G01X969700Y15680D02*
X971460D01*
G01X969700Y15840D02*
X971460D01*
G01X969700Y16000D02*
X971460D01*
G01X969700Y16160D02*
X971460D01*
G01X969700Y16320D02*
X971460D01*
G01X969700Y16480D02*
X971460D01*
G01X969700Y16640D02*
X971460D01*
G01X969700Y16800D02*
X971460D01*
G01X969700Y16960D02*
X971460D01*
G01X969700Y17120D02*
X971460D01*
G01X969700Y17280D02*
X971460D01*
G01X969700Y17440D02*
X971460D01*
G01X969700Y17600D02*
X971460D01*
G01X969700Y17760D02*
X971460D01*
G01X969700Y17920D02*
X971300D01*
G01X969700Y18080D02*
X971300D01*
G01X969700Y18240D02*
X971300D01*
G01X969700Y18400D02*
X973060D01*
G01X969700Y18560D02*
X973060D01*
G01X969700Y18720D02*
X972900D01*
G01X969700Y18880D02*
X972900D01*
G01X969700Y19040D02*
X972740D01*
G01X969700Y19200D02*
X972740D01*
G01X969700Y19360D02*
X972740D01*
G01X969700Y19520D02*
X972580D01*
G01X969700Y19680D02*
X972580D01*
G01X969700Y19840D02*
X972420D01*
G01X969700Y20000D02*
X972420D01*
G01X969700Y20160D02*
X972420D01*
G01X969700Y20320D02*
X972260D01*
G01X974500Y10560D02*
X976420D01*
G01X974500Y10720D02*
X976580D01*
G01X974340Y10880D02*
X976580D01*
G01X974340Y11040D02*
X976580D01*
G01X974340Y11200D02*
X976740D01*
G01X974180Y11360D02*
X976740D01*
G01X974180Y11520D02*
X976900D01*
G01X974020Y11680D02*
X976900D01*
G01X974020Y11840D02*
X976900D01*
G01X974020Y12000D02*
X977060D01*
G01X973860Y12160D02*
X975460D01*
G01X973860Y12320D02*
X975460D01*
G01X973700Y12480D02*
X975460D01*
G01X973700Y12640D02*
X975300D01*
G01X973700Y12800D02*
X975300D01*
G01X973540Y12960D02*
X975140D01*
G01X973540Y13120D02*
X975140D01*
G01X973380Y13280D02*
X975140D01*
G01X973380Y13440D02*
X974980D01*
G01X973380Y13600D02*
X974980D01*
G01X973220Y13760D02*
X974820D01*
G01X973220Y13920D02*
X974820D01*
G01X973060Y14080D02*
X974820D01*
G01X973060Y14240D02*
X974660D01*
G01X973060Y14400D02*
X974660D01*
G01X972900Y14560D02*
X974500D01*
G01X972900Y14720D02*
X974500D01*
G01X972740Y14880D02*
X974500D01*
G01X972740Y15040D02*
X974340D01*
G01X972740Y15200D02*
X974340D01*
G01X972580Y15360D02*
X974180D01*
G01X972580Y15520D02*
X974180D01*
G01X972420Y15680D02*
X974180D01*
G01X972420Y15840D02*
X974020D01*
G01X972260Y16000D02*
X974020D01*
G01X972260Y16160D02*
X974020D01*
G01X972260Y16320D02*
X973860D01*
G01X972100Y16480D02*
X973860D01*
G01X972100Y16640D02*
X973700D01*
G01X971940Y16800D02*
X973700D01*
G01X971940Y16960D02*
X973700D01*
G01X971940Y17120D02*
X973540D01*
G01X971780Y17280D02*
X973540D01*
G01X971780Y17440D02*
X973380D01*
G01X971620Y17600D02*
X973380D01*
G01X971620Y17760D02*
X973380D01*
G01X971620Y17920D02*
X973220D01*
G01X971460Y18080D02*
X973220D01*
G01X971460Y18240D02*
X973060D01*
G01X990180Y9600D02*
X991940D01*
G01X994980Y9760D02*
X996740D01*
G01X989700D02*
X992580D01*
G01X983780D02*
X985540D01*
G01X979620D02*
X981380D01*
G01X974820D02*
X976100D01*
G01X994980Y9920D02*
X996740D01*
G01X989220D02*
X993060D01*
G01X983780D02*
X985540D01*
G01X979620D02*
X981380D01*
G01X974820D02*
X976260D01*
G01X994980Y10080D02*
X996740D01*
G01X989060D02*
X993220D01*
G01X983780D02*
X985540D01*
G01X979620D02*
X981380D01*
G01X974820D02*
X976260D01*
G01X994980Y10240D02*
X996740D01*
G01X988740D02*
X993220D01*
G01X983780D02*
X985540D01*
G01X979620D02*
X981380D01*
G01X974660D02*
X976260D01*
G01X994980Y10400D02*
X996740D01*
G01X988580D02*
X993220D01*
G01X983780D02*
X985540D01*
G01X979620D02*
X981380D01*
G01X974660D02*
X976420D01*
G01X994980Y10560D02*
X996740D01*
G01X988420D02*
X993220D01*
G01X983780D02*
X985540D01*
G01X979620D02*
X981380D01*
G01X994980Y10720D02*
X996740D01*
G01X988260D02*
X993220D01*
G01X983780D02*
X985540D01*
G01X979620D02*
X981380D01*
G01X994980Y10880D02*
X996740D01*
G01X988100D02*
X993220D01*
G01X983780D02*
X985540D01*
G01X979620D02*
X981380D01*
G01X994980Y11040D02*
X996740D01*
G01X992260D02*
X993220D01*
G01X987940D02*
X990820D01*
G01X983780D02*
X985540D01*
G01X979620D02*
X981380D01*
G01X994980Y11200D02*
X996740D01*
G01X992580D02*
X993220D01*
G01X987940D02*
X990340D01*
G01X983780D02*
X985540D01*
G01X979620D02*
X981380D01*
G01X994980Y11360D02*
X996740D01*
G01X992900D02*
X993220D01*
G01X987780D02*
X990020D01*
G01X983780D02*
X985540D01*
G01X979620D02*
X981380D01*
G01X994980Y11520D02*
X996740D01*
G01X987620D02*
X989860D01*
G01X983780D02*
X985540D01*
G01X979620D02*
X981380D01*
G01X994980Y11680D02*
X996740D01*
G01X987620D02*
X989700D01*
G01X983780D02*
X985540D01*
G01X979620D02*
X981380D01*
G01X994980Y11840D02*
X996740D01*
G01X987620D02*
X989540D01*
G01X983780D02*
X985540D01*
G01X979620D02*
X981380D01*
G01X994980Y12000D02*
X996740D01*
G01X987460D02*
X989380D01*
G01X983780D02*
X985540D01*
G01X979620D02*
X981380D01*
G01X994980Y12160D02*
X996740D01*
G01X987460D02*
X989380D01*
G01X983780D02*
X985540D01*
G01X979620D02*
X981380D01*
G01X975620D02*
X977060D01*
G01X994980Y12320D02*
X996740D01*
G01X987460D02*
X989220D01*
G01X983780D02*
X985540D01*
G01X979620D02*
X981380D01*
G01X975620D02*
X977220D01*
G01X994980Y12480D02*
X996740D01*
G01X987460D02*
X989220D01*
G01X983780D02*
X985540D01*
G01X979620D02*
X981380D01*
G01X975780D02*
X977220D01*
G01X994980Y12640D02*
X996740D01*
G01X987300D02*
X989220D01*
G01X983780D02*
X985540D01*
G01X979620D02*
X981380D01*
G01X975780D02*
X977380D01*
G01X994980Y12800D02*
X996740D01*
G01X987300D02*
X989060D01*
G01X983780D02*
X985540D01*
G01X979620D02*
X981380D01*
G01X975780D02*
X977380D01*
G01X994980Y12960D02*
X996740D01*
G01X987300D02*
X989060D01*
G01X983780D02*
X985540D01*
G01X979620D02*
X981380D01*
G01X975940D02*
X977380D01*
G01X994980Y13120D02*
X996740D01*
G01X987300D02*
X989060D01*
G01X983780D02*
X985540D01*
G01X979620D02*
X981380D01*
G01X975940D02*
X977540D01*
G01X994980Y13280D02*
X996740D01*
G01X987300D02*
X989060D01*
G01X983780D02*
X985540D01*
G01X979620D02*
X981380D01*
G01X976100D02*
X977540D01*
G01X994980Y13440D02*
X996740D01*
G01X987300D02*
X989060D01*
G01X983780D02*
X985540D01*
G01X979620D02*
X981380D01*
G01X976100D02*
X977700D01*
G01X994980Y13600D02*
X996740D01*
G01X987300D02*
X989060D01*
G01X983780D02*
X985540D01*
G01X979620D02*
X981380D01*
G01X976100D02*
X977700D01*
G01X994980Y13760D02*
X996740D01*
G01X987300D02*
X989060D01*
G01X983780D02*
X985540D01*
G01X979620D02*
X981380D01*
G01X976260D02*
X977700D01*
G01X994980Y13920D02*
X996740D01*
G01X987300D02*
X989060D01*
G01X983780D02*
X985540D01*
G01X979620D02*
X981380D01*
G01X976260D02*
X977860D01*
G01X994980Y14080D02*
X996740D01*
G01X987300D02*
X989060D01*
G01X983780D02*
X985540D01*
G01X979620D02*
X981380D01*
G01X976420D02*
X977860D01*
G01X994980Y14240D02*
X996900D01*
G01X987300D02*
X989220D01*
G01X983780D02*
X985540D01*
G01X979620D02*
X981380D01*
G01X976420D02*
X978020D01*
G01X994980Y14400D02*
X996900D01*
G01X987460D02*
X989220D01*
G01X983780D02*
X985540D01*
G01X979620D02*
X981380D01*
G01X976420D02*
X978020D01*
G01X994980Y14560D02*
X996900D01*
G01X987460D02*
X989220D01*
G01X983780D02*
X985540D01*
G01X979620D02*
X981380D01*
G01X976580D02*
X978020D01*
G01X994980Y14720D02*
X997060D01*
G01X987460D02*
X989380D01*
G01X983780D02*
X985540D01*
G01X979620D02*
X981380D01*
G01X976580D02*
X978180D01*
G01X994980Y14880D02*
X997060D01*
G01X987460D02*
X989380D01*
G01X983780D02*
X985540D01*
G01X979620D02*
X981380D01*
G01X976740D02*
X978180D01*
G01X994980Y15040D02*
X997220D01*
G01X987620D02*
X989540D01*
G01X983780D02*
X985540D01*
G01X979620D02*
X981380D01*
G01X976740D02*
X978340D01*
G01X994980Y15200D02*
X997220D01*
G01X987620D02*
X989700D01*
G01X983780D02*
X985540D01*
G01X979620D02*
X981380D01*
G01X976740D02*
X978340D01*
G01X994980Y15360D02*
X997380D01*
G01X987780D02*
X989860D01*
G01X983780D02*
X985540D01*
G01X979620D02*
X981380D01*
G01X976900D02*
X978340D01*
G01X994980Y15520D02*
X997540D01*
G01X987780D02*
X990020D01*
G01X983780D02*
X985540D01*
G01X979620D02*
X981380D01*
G01X976900D02*
X978500D01*
G01X994980Y15680D02*
X997700D01*
G01X992900D02*
X993220D01*
G01X987940D02*
X990180D01*
G01X983780D02*
X985540D01*
G01X979620D02*
X981380D01*
G01X977060D02*
X978500D01*
G01X994980Y15840D02*
X998020D01*
G01X992740D02*
X993220D01*
G01X987940D02*
X990500D01*
G01X983780D02*
X985540D01*
G01X979620D02*
X981380D01*
G01X977060D02*
X978660D01*
G01X996900Y16000D02*
X999460D01*
G01X994980D02*
X996740D01*
G01X992260D02*
X993220D01*
G01X988100D02*
X990820D01*
G01X983780D02*
X985540D01*
G01X979620D02*
X981380D01*
G01X977060D02*
X978660D01*
G01X996900Y16160D02*
X999460D01*
G01X994980D02*
X996740D01*
G01X988260D02*
X993220D01*
G01X983780D02*
X985540D01*
G01X979620D02*
X981380D01*
G01X977220D02*
X978660D01*
G01X997060Y16320D02*
X999460D01*
G01X994980D02*
X996740D01*
G01X988420D02*
X993220D01*
G01X983780D02*
X985540D01*
G01X979620D02*
X981380D01*
G01X977220D02*
X978820D01*
G01X997060Y16480D02*
X999460D01*
G01X994980D02*
X996740D01*
G01X988580D02*
X993220D01*
G01X983780D02*
X985540D01*
G01X979620D02*
X981380D01*
G01X977380D02*
X978820D01*
G01X997220Y16640D02*
X999460D01*
G01X994980D02*
X996740D01*
G01X988740D02*
X993220D01*
G01X983780D02*
X985540D01*
G01X979620D02*
X981380D01*
G01X977380D02*
X978980D01*
G01X997380Y16800D02*
X999460D01*
G01X994980D02*
X996740D01*
G01X988900D02*
X993220D01*
G01X983780D02*
X985540D01*
G01X979620D02*
X981380D01*
G01X977540D02*
X978980D01*
G01X997540Y16960D02*
X999460D01*
G01X994980D02*
X996740D01*
G01X989220D02*
X993220D01*
G01X983780D02*
X985540D01*
G01X979620D02*
X981380D01*
G01X977540D02*
X978980D01*
G01X994980Y17120D02*
X996740D01*
G01X989540D02*
X993220D01*
G01X983780D02*
X985540D01*
G01X979620D02*
X981380D01*
G01X977540D02*
X979140D01*
G01X994980Y17280D02*
X996740D01*
G01X989860D02*
X992900D01*
G01X983780D02*
X985540D01*
G01X979620D02*
X981380D01*
G01X977700D02*
X979140D01*
G01X990500Y17440D02*
X992260D01*
G01X979620D02*
X981380D01*
G01X977700D02*
X979300D01*
G01X979620Y17600D02*
X981380D01*
G01X977860D02*
X979300D01*
G01X979620Y17760D02*
X981380D01*
G01X977860D02*
X979300D01*
G01X979620Y17920D02*
X981380D01*
G01X977860D02*
X979460D01*
G01X979620Y18080D02*
X981380D01*
G01X978020D02*
X979460D01*
G01X979620Y18240D02*
X981380D01*
G01X978020D02*
X979460D01*
G01X978180Y18400D02*
X981380D01*
G01X978180Y18560D02*
X981380D01*
G01X978180Y18720D02*
X981380D01*
G01X978340Y18880D02*
X981380D01*
G01X984260Y19040D02*
X985060D01*
G01X978340D02*
X981380D01*
G01X983940Y19200D02*
X985380D01*
G01X978500D02*
X981380D01*
G01X983780Y19360D02*
X985540D01*
G01X978500D02*
X981380D01*
G01X983780Y19520D02*
X985540D01*
G01X978500D02*
X981380D01*
G01X983620Y19680D02*
X985700D01*
G01X978660D02*
X981380D01*
G01X983620Y19840D02*
X985700D01*
G01X978660D02*
X981380D01*
G01X983620Y20000D02*
X985700D01*
G01X978820D02*
X981380D01*
G01X983620Y20160D02*
X985700D01*
G01X978820D02*
X981380D01*
G01X983780Y20320D02*
X985540D01*
G01X978820D02*
X981380D01*
G01X983780Y20480D02*
X985540D01*
G01X983940Y20640D02*
X985380D01*
G01X984260Y20800D02*
X985060D01*
G01X999140Y15840D02*
X999460D01*
G01X997700Y17120D02*
X999460D01*
G01X997860Y17280D02*
X999460D01*
G01X998340Y17440D02*
X999300D01*
G01X1018980Y9600D02*
X1020740D01*
G01X1010660D02*
X1012420D01*
G01X1003300D02*
X1005060D01*
G01X1018340Y9760D02*
X1021380D01*
G01X1010020D02*
X1013220D01*
G01X1002660D02*
X1005700D01*
G01X1017860Y9920D02*
X1021700D01*
G01X1009540D02*
X1013540D01*
G01X1002180D02*
X1006020D01*
G01X1017700Y10080D02*
X1022020D01*
G01X1009380D02*
X1013860D01*
G01X1002020D02*
X1006340D01*
G01X1017380Y10240D02*
X1022340D01*
G01X1009380D02*
X1014020D01*
G01X1001700D02*
X1006660D01*
G01X1017220Y10400D02*
X1022500D01*
G01X1009380D02*
X1014180D01*
G01X1001540D02*
X1006820D01*
G01X1017060Y10560D02*
X1022660D01*
G01X1009380D02*
X1014340D01*
G01X1001380D02*
X1006980D01*
G01X1016900Y10720D02*
X1022820D01*
G01X1009380D02*
X1014500D01*
G01X1001220D02*
X1007140D01*
G01X1016740Y10880D02*
X1022980D01*
G01X1009380D02*
X1014500D01*
G01X1001060D02*
X1007300D01*
G01X1016580Y11040D02*
X1019300D01*
G01X1012420D02*
X1014660D01*
G01X1009380D02*
X1010820D01*
G01X1004900D02*
X1007460D01*
G01X1000900D02*
X1003620D01*
G01X1016580Y11200D02*
X1018820D01*
G01X1012740D02*
X1014660D01*
G01X1009380D02*
X1010340D01*
G01X1005220D02*
X1007460D01*
G01X1000900D02*
X1003140D01*
G01X1016420Y11360D02*
X1018660D01*
G01X1012900D02*
X1014820D01*
G01X1009380D02*
X1010020D01*
G01X1005540D02*
X1007620D01*
G01X1000740D02*
X1002980D01*
G01X1016420Y11520D02*
X1018340D01*
G01X1013060D02*
X1014820D01*
G01X1009380D02*
X1009700D01*
G01X1005700D02*
X1007620D01*
G01X1000740D02*
X1002660D01*
G01X1016260Y11680D02*
X1018340D01*
G01X1013060D02*
X1014820D01*
G01X1005860D02*
X1007780D01*
G01X1000580D02*
X1002660D01*
G01X1016260Y11840D02*
X1018180D01*
G01X1013060D02*
X1014820D01*
G01X1006020D02*
X1007780D01*
G01X1000580D02*
X1002500D01*
G01X1016100Y12000D02*
X1018020D01*
G01X1013060D02*
X1014820D01*
G01X1006020D02*
X1007940D01*
G01X1000420D02*
X1002340D01*
G01X1016100Y12160D02*
X1018020D01*
G01X1012900D02*
X1014820D01*
G01X1006180D02*
X1007940D01*
G01X1000420D02*
X1002340D01*
G01X1016100Y12320D02*
X1017860D01*
G01X1012900D02*
X1014820D01*
G01X1006180D02*
X1007940D01*
G01X1000420D02*
X1002180D01*
G01X1016100Y12480D02*
X1017860D01*
G01X1012580D02*
X1014660D01*
G01X1006180D02*
X1007940D01*
G01X1000420D02*
X1002180D01*
G01X1015940Y12640D02*
X1017860D01*
G01X1012420D02*
X1014660D01*
G01X1006340D02*
X1008100D01*
G01X1000260D02*
X1002180D01*
G01X1015940Y12800D02*
X1017700D01*
G01X1011940D02*
X1014500D01*
G01X1006340D02*
X1008100D01*
G01X1000260D02*
X1002020D01*
G01X1015940Y12960D02*
X1017700D01*
G01X1011460D02*
X1014500D01*
G01X1006340D02*
X1008100D01*
G01X1000260D02*
X1002020D01*
G01X1015940Y13120D02*
X1017700D01*
G01X1011140D02*
X1014340D01*
G01X1006340D02*
X1008100D01*
G01X1000260D02*
X1002020D01*
G01X1015940Y13280D02*
X1017700D01*
G01X1010820D02*
X1014180D01*
G01X1006340D02*
X1008100D01*
G01X1000260D02*
X1002020D01*
G01X1015940Y13440D02*
X1017700D01*
G01X1010500D02*
X1014020D01*
G01X1006340D02*
X1008100D01*
G01X1000260D02*
X1002020D01*
G01X1015940Y13600D02*
X1017700D01*
G01X1010180D02*
X1013700D01*
G01X1006340D02*
X1008100D01*
G01X1000260D02*
X1002020D01*
G01X1015940Y13760D02*
X1017700D01*
G01X1010020D02*
X1013540D01*
G01X1006340D02*
X1008100D01*
G01X1000260D02*
X1002020D01*
G01X1015940Y13920D02*
X1017700D01*
G01X1009860D02*
X1013220D01*
G01X1006340D02*
X1008100D01*
G01X1000260D02*
X1002020D01*
G01X1015940Y14080D02*
X1017700D01*
G01X1009700D02*
X1012740D01*
G01X1006340D02*
X1008100D01*
G01X1000260D02*
X1002020D01*
G01X1015940Y14240D02*
X1017700D01*
G01X1009700D02*
X1012420D01*
G01X1006340D02*
X1008100D01*
G01X1000260D02*
X1002020D01*
G01X1016100Y14400D02*
X1017860D01*
G01X1009540D02*
X1011940D01*
G01X1006180D02*
X1008100D01*
G01X1000420D02*
X1002180D01*
G01X1016100Y14560D02*
X1017860D01*
G01X1009540D02*
X1011620D01*
G01X1006180D02*
X1008100D01*
G01X1000420D02*
X1002180D01*
G01X1016100Y14720D02*
X1017860D01*
G01X1009540D02*
X1011300D01*
G01X1006180D02*
X1007940D01*
G01X1000420D02*
X1002180D01*
G01X1016100Y14880D02*
X1018020D01*
G01X1009380D02*
X1011300D01*
G01X1006180D02*
X1007940D01*
G01X1000420D02*
X1002340D01*
G01X1016260Y15040D02*
X1018020D01*
G01X1009380D02*
X1011140D01*
G01X1006020D02*
X1007940D01*
G01X1000580D02*
X1002340D01*
G01X1016260Y15200D02*
X1018180D01*
G01X1009380D02*
X1011140D01*
G01X1006020D02*
X1007940D01*
G01X1000580D02*
X1002500D01*
G01X1016260Y15360D02*
X1018340D01*
G01X1009380D02*
X1011140D01*
G01X1005860D02*
X1007780D01*
G01X1000580D02*
X1002660D01*
G01X1016420Y15520D02*
X1018340D01*
G01X1009380D02*
X1011140D01*
G01X1005700D02*
X1007780D01*
G01X1000740D02*
X1002660D01*
G01X1016420Y15680D02*
X1018660D01*
G01X1009380D02*
X1011300D01*
G01X1005540D02*
X1007620D01*
G01X1000740D02*
X1002980D01*
G01X1016580Y15840D02*
X1018820D01*
G01X1013860D02*
X1014340D01*
G01X1009540D02*
X1011460D01*
G01X1005220D02*
X1007620D01*
G01X1000900D02*
X1003140D01*
G01X1016740Y16000D02*
X1019300D01*
G01X1013380D02*
X1014340D01*
G01X1009540D02*
X1011780D01*
G01X1004900D02*
X1007460D01*
G01X1001060D02*
X1003620D01*
G01X1016740Y16160D02*
X1022980D01*
G01X1009700D02*
X1014340D01*
G01X1001060D02*
X1007300D01*
G01X1016900Y16320D02*
X1022980D01*
G01X1009700D02*
X1014340D01*
G01X1001220D02*
X1007300D01*
G01X1017060Y16480D02*
X1022820D01*
G01X1009860D02*
X1014340D01*
G01X1001380D02*
X1007140D01*
G01X1017220Y16640D02*
X1022660D01*
G01X1010020D02*
X1014340D01*
G01X1001540D02*
X1006980D01*
G01X1017540Y16800D02*
X1022340D01*
G01X1010180D02*
X1014340D01*
G01X1001860D02*
X1006660D01*
G01X1017700Y16960D02*
X1022180D01*
G01X1010340D02*
X1014340D01*
G01X1002020D02*
X1006500D01*
G01X1018020Y17120D02*
X1021860D01*
G01X1010660D02*
X1014340D01*
G01X1002340D02*
X1006180D01*
G01X1018500Y17280D02*
X1021540D01*
G01X1011140D02*
X1014180D01*
G01X1002820D02*
X1005860D01*
G01X1019140Y17440D02*
X1020900D01*
G01X1011620D02*
X1013540D01*
G01X1003460D02*
X1005220D01*
G01X1026180Y9760D02*
X1027780D01*
G01X1026180Y9920D02*
X1027780D01*
G01X1026180Y10080D02*
X1027780D01*
G01X1026180Y10240D02*
X1027780D01*
G01X1026180Y10400D02*
X1027780D01*
G01X1026180Y10560D02*
X1027780D01*
G01X1026180Y10720D02*
X1027780D01*
G01X1026180Y10880D02*
X1027780D01*
G01X1026180Y11040D02*
X1027780D01*
G01X1020580D02*
X1023140D01*
G01X1026180Y11200D02*
X1027780D01*
G01X1020900D02*
X1023140D01*
G01X1026180Y11360D02*
X1027780D01*
G01X1021220D02*
X1023300D01*
G01X1026180Y11520D02*
X1027780D01*
G01X1021380D02*
X1023300D01*
G01X1026180Y11680D02*
X1027780D01*
G01X1021540D02*
X1023460D01*
G01X1026180Y11840D02*
X1027780D01*
G01X1021700D02*
X1023460D01*
G01X1026180Y12000D02*
X1027780D01*
G01X1021700D02*
X1023620D01*
G01X1026180Y12160D02*
X1027780D01*
G01X1021860D02*
X1023620D01*
G01X1026180Y12320D02*
X1027780D01*
G01X1021860D02*
X1023620D01*
G01X1026180Y12480D02*
X1027780D01*
G01X1021860D02*
X1023620D01*
G01X1026180Y12640D02*
X1027780D01*
G01X1022020D02*
X1023780D01*
G01X1026180Y12800D02*
X1027780D01*
G01X1022020D02*
X1023780D01*
G01X1026180Y12960D02*
X1027780D01*
G01X1022020D02*
X1023780D01*
G01X1026180Y13120D02*
X1027780D01*
G01X1022020D02*
X1023780D01*
G01X1026180Y13280D02*
X1027780D01*
G01X1022020D02*
X1023780D01*
G01X1026180Y13440D02*
X1027780D01*
G01X1022020D02*
X1023780D01*
G01X1026180Y13600D02*
X1027780D01*
G01X1022020D02*
X1023780D01*
G01X1026180Y13760D02*
X1027780D01*
G01X1022020D02*
X1023780D01*
G01X1026180Y13920D02*
X1027780D01*
G01X1022020D02*
X1023780D01*
G01X1026180Y14080D02*
X1027780D01*
G01X1022020D02*
X1023780D01*
G01X1026180Y14240D02*
X1027780D01*
G01X1022020D02*
X1023780D01*
G01X1026180Y14400D02*
X1027780D01*
G01X1021860D02*
X1023780D01*
G01X1026180Y14560D02*
X1027780D01*
G01X1021860D02*
X1023780D01*
G01X1026180Y14720D02*
X1027780D01*
G01X1021860D02*
X1023620D01*
G01X1026180Y14880D02*
X1027780D01*
G01X1021860D02*
X1023620D01*
G01X1026180Y15040D02*
X1027780D01*
G01X1021700D02*
X1023620D01*
G01X1026180Y15200D02*
X1027780D01*
G01X1021700D02*
X1023620D01*
G01X1026180Y15360D02*
X1027780D01*
G01X1021540D02*
X1023460D01*
G01X1026180Y15520D02*
X1027780D01*
G01X1021380D02*
X1023460D01*
G01X1026180Y15680D02*
X1027780D01*
G01X1021220D02*
X1023300D01*
G01X1026180Y15840D02*
X1027780D01*
G01X1020900D02*
X1023300D01*
G01X1030020Y16000D02*
X1034820D01*
G01X1024740D02*
X1030040D01*
G01X1020580D02*
X1023140D01*
G01X1030020Y16160D02*
X1034820D01*
G01X1024740D02*
X1030040D01*
G01X1030020Y16320D02*
X1034820D01*
G01X1024740D02*
X1030040D01*
G01X1030020Y16480D02*
X1034820D01*
G01X1024740D02*
X1030040D01*
G01X1030020Y16640D02*
X1034820D01*
G01X1024740D02*
X1029540D01*
G01X1030020Y16800D02*
X1034820D01*
G01X1024740D02*
X1030040D01*
G01X1030020Y16960D02*
X1034820D01*
G01X1024740D02*
X1029540D01*
G01X1030020Y17120D02*
X1034820D01*
G01X1024740D02*
X1030040D01*
G01X1030020Y17280D02*
X1034820D01*
G01X1024740D02*
X1030040D01*
G01X1026180Y17440D02*
X1027780D01*
G01X1026180Y17600D02*
X1027780D01*
G01X1026180Y17760D02*
X1027780D01*
G01X1026180Y17920D02*
X1027780D01*
G01X1026180Y18080D02*
X1027780D01*
G01X1026180Y18240D02*
X1027780D01*
G01X1026180Y18400D02*
X1027780D01*
G01X1026180Y18560D02*
X1027780D01*
G01X1026180Y18720D02*
X1027780D01*
G01X1026180Y18880D02*
X1027940D01*
G01X1026180Y19040D02*
X1027940D01*
G01X1026180Y19200D02*
X1027940D01*
G01X1026180Y19360D02*
X1028100D01*
G01X1026180Y19520D02*
X1028260D01*
G01X1029700Y19680D02*
X1029860D01*
G01X1026340D02*
X1028580D01*
G01X1026340Y19840D02*
X1029860D01*
G01X1026500Y20000D02*
X1029860D01*
G01X1026660Y20160D02*
X1029860D01*
G01X1026660Y20320D02*
X1029860D01*
G01X1026820Y20480D02*
X1029860D01*
G01X1027140Y20640D02*
X1029860D01*
G01X1027300Y20800D02*
X1029860D01*
G01X1027620Y20960D02*
X1029860D01*
G01X1028100Y21120D02*
X1029700D01*
G01X1032740Y9600D02*
X1034340D01*
G01X1032260Y9760D02*
X1034820D01*
G01X1032100Y9920D02*
X1034820D01*
G01X1031940Y10080D02*
X1034820D01*
G01X1031780Y10240D02*
X1034820D01*
G01X1031620Y10400D02*
X1034820D01*
G01X1031620Y10560D02*
X1034820D01*
G01X1031460Y10720D02*
X1034820D01*
G01X1031460Y10880D02*
X1034820D01*
G01X1034500Y11040D02*
X1034820D01*
G01X1031460D02*
X1033540D01*
G01X1031300Y11200D02*
X1033380D01*
G01X1031300Y11360D02*
X1033220D01*
G01X1031300Y11520D02*
X1033220D01*
G01X1031300Y11680D02*
X1033060D01*
G01X1031300Y11840D02*
X1033060D01*
G01X1031300Y12000D02*
X1033060D01*
G01X1031300Y12160D02*
X1033060D01*
G01X1031300Y12320D02*
X1033060D01*
G01X1031300Y12480D02*
X1033060D01*
G01X1031300Y12640D02*
X1033060D01*
G01X1031300Y12800D02*
X1033060D01*
G01X1031300Y12960D02*
X1033060D01*
G01X1031300Y13120D02*
X1033060D01*
G01X1031300Y13280D02*
X1033060D01*
G01X1031300Y13440D02*
X1033060D01*
G01X1031300Y13600D02*
X1033060D01*
G01X1031300Y13760D02*
X1033060D01*
G01X1031300Y13920D02*
X1033060D01*
G01X1031300Y14080D02*
X1033060D01*
G01X1031300Y14240D02*
X1033060D01*
G01X1031300Y14400D02*
X1033060D01*
G01X1031300Y14560D02*
X1033060D01*
G01X1031300Y14720D02*
X1033060D01*
G01X1031300Y14880D02*
X1033060D01*
G01X1031300Y15040D02*
X1033060D01*
G01X1031300Y15200D02*
X1033060D01*
G01X1031300Y15360D02*
X1033060D01*
G01X1031300Y15520D02*
X1033060D01*
G01X1031300Y15680D02*
X1033060D01*
G01X1031300Y15840D02*
X1033060D01*
G01X1031300Y17440D02*
X1033060D01*
G01X1031300Y17600D02*
X1033060D01*
G01X1031300Y17760D02*
X1033060D01*
G01X1031300Y17920D02*
X1033060D01*
G01X1031300Y18080D02*
X1033060D01*
G01X1031300Y18240D02*
X1033060D01*
G01X1031300Y18400D02*
X1033060D01*
G01X1031300Y18560D02*
X1033060D01*
G01X1031300Y18720D02*
X1033060D01*
G01X1031300Y18880D02*
X1033060D01*
G01X1031300Y19040D02*
X1033060D01*
G01X1031620Y19200D02*
X1033060D01*
G01X1032260Y19360D02*
X1033060D01*
G01X1032740Y19520D02*
X1033060D01*
M02*
